G04 ================== begin FILE IDENTIFICATION RECORD ==================*
G04 Layout Name:  12433-2a.brd*
G04 Film Name:    L4*
G04 File Format:  Gerber RS274X*
G04 File Origin:  Cadence Allegro 16.5-S056*
G04 Origin Date:  Fri Dec 11 16:47:41 2015*
G04 *
G04 Layer:  VIA CLASS/BOTTOM*
G04 Layer:  PIN/BOTTOM*
G04 Layer:  ETCH/BOTTOM*
G04 Layer:  DRAWING FORMAT/LAYER_PCB_STORY*
G04 Layer:  DRAWING FORMAT/LAYER_L4*
G04 *
G04 Offset:    (0.00 0.00)*
G04 Mirror:    No*
G04 Mode:      Positive*
G04 Rotation:  0*
G04 FullContactRelief:  No*
G04 UndefLineWidth:     6.00*
G04 ================== end FILE IDENTIFICATION RECORD ====================*
%FSLAX35Y35*MOIN*%
%IR0*IPPOS*OFA0.00000B0.00000*MIA0B0*SFA1.00000B1.00000*%
%ADD10C,.01*%
%ADD15C,.022*%
%ADD16C,.05*%
%ADD12C,.028*%
%ADD13C,.056*%
%ADD17C,.057*%
%ADD11R,.05X.05*%
%ADD14C,.315*%
%ADD18C,.375*%
%ADD19C,.02*%
%ADD20C,.04*%
%ADD21C,.025*%
%ADD22C,.006*%
%ADD23C,.0055*%
%ADD27C,.05204*%
%ADD28C,.08004*%
%ADD29C,.08104*%
%ADD30C,.04604*%
%ADD31C,.07404*%
%ADD24R,.13204X.13204*%
%ADD33C,.15004*%
%ADD32C,.12304*%
%ADD35C,.16604*%
%ADD34C,.13904*%
%ADD25C,.33904*%
%ADD26C,.39904*%
G75*
%LPD*%
G75*
G36*
G01X3001Y1964567D02*
G02X3937Y1965503I936J0D01*
G01X64961D01*
G02X65897Y1964567I0J-936D01*
G01Y1933071D01*
G03X72835Y1926133I6938J0D01*
G01X202756D01*
G02X203692Y1925197I0J-936D01*
G01Y525539D01*
G02X202999Y525268I-400J1D01*
G03X199322Y521590I-1910J-1768D01*
G02X199337Y521017I-271J-294D01*
G03X203013Y517334I1862J-1817D01*
G02X203692Y517047I279J-287D01*
G01Y484437D01*
G02X203009Y484155I-400J1D01*
G01X200673Y486492D01*
G02X200761Y487124I283J283D01*
G03X198374Y491746I-1260J2277D01*
G02X197801Y492106I-173J361D01*
G01Y495954D01*
G02X198481Y496239I400J-1D01*
G03Y499961I1819J1861D01*
G02X197802Y500247I-279J286D01*
G01Y503459D01*
G02X198414Y503798I400J0D01*
G03Y508202I1386J2202D01*
G02X197802Y508541I-212J339D01*
G01Y511275D01*
G02X198454Y511584I400J-1D01*
G03Y515616I1646J2016D01*
G02X197802Y515925I-252J310D01*
G01Y529163D01*
X184882Y542082D01*
X184887Y542170D01*
G03X180401Y543007I-2299J118D01*
G02X179739Y542850I-379J126D01*
G01X161676Y560912D01*
X161789Y561052D01*
G03X158458Y560791I-1789J1448D01*
G01X158524Y560731D01*
Y560455D01*
G02X157841Y560172I-400J0D01*
G01X152802Y565212D01*
Y579188D01*
G02X153408Y579530I400J0D01*
G03Y583470I1192J1970D01*
G02X152801Y583812I-207J342D01*
G01Y585213D01*
X156681Y589093D01*
G02X157302Y589023I283J-283D01*
G03X160477Y592198I1948J1227D01*
G02X160407Y592819I213J338D01*
G01X185276Y617688D01*
Y642312D01*
X182576Y645012D01*
Y689412D01*
X173776Y698212D01*
Y726838D01*
X169602Y731013D01*
Y761089D01*
X183802Y775289D01*
Y947113D01*
X185652Y948963D01*
Y984837D01*
X181476Y989012D01*
Y999112D01*
X150476Y1030112D01*
Y1095112D01*
X143976Y1101612D01*
Y1418734D01*
G03X142501Y1422802I-1476J1766D01*
G02X142102Y1423202I1J400D01*
G01Y1441466D01*
X149019Y1448384D01*
G02X149702Y1448101I283J-283D01*
G01Y1440812D01*
G03X149794Y1440557I400J0D01*
G02X149784Y1440035I-308J-255D01*
G03X153795Y1438320I1716J-1535D01*
G01X153801Y1438394D01*
X157702Y1442295D01*
Y1445531D01*
G03X158600Y1447602I-1702J1968D01*
G01X158597Y1447690D01*
X159202Y1448295D01*
Y1453249D01*
G03X155753Y1456299I-1702J1551D01*
G02X155056Y1456485I-304J260D01*
G03X154731Y1457340I-2557J-483D01*
G01X154702Y1457388D01*
Y1457986D01*
X160702Y1463986D01*
Y1465827D01*
X160710Y1465854D01*
G03X156298Y1465827I-2210J645D01*
G01Y1465810D01*
X150298Y1459810D01*
Y1458202D01*
X149612D01*
X146902Y1460912D01*
Y1460914D01*
X114364Y1493452D01*
X113423D01*
X113396Y1493460D01*
G03X112566Y1488955I-645J-2210D01*
G01X112639Y1488949D01*
X142498Y1459090D01*
Y1459088D01*
X147788Y1453798D01*
X147857D01*
X147959Y1453551D01*
X137698Y1443290D01*
Y1418302D01*
G02X137047Y1417991I-400J0D01*
G03X136638Y1418255I-1446J-1791D01*
G02X136475Y1418818I180J357D01*
G03X135863Y1421855I-1975J1182D01*
G02X135817Y1422460I237J322D01*
G01X136302Y1422944D01*
Y1439987D01*
G03X131830Y1442400I-2503J712D01*
G01X124985D01*
X122690Y1440106D01*
X122602Y1440109D01*
G03X119900Y1437407I-102J-2600D01*
G01X119903Y1437319D01*
X119486Y1436902D01*
X118971D01*
X118911Y1436966D01*
G03X115139Y1433381I-1911J-1766D01*
G02X114853Y1432702I-286J-279D01*
G01X110795D01*
X109894Y1431801D01*
X109820Y1431795D01*
G03X112272Y1429130I180J-2295D01*
G01X112299Y1429298D01*
X122205D01*
X127705Y1434798D01*
X130449D01*
G03X132425Y1434238I1550J1702D01*
G02X132898Y1433846I73J-393D01*
G01Y1424354D01*
X129472Y1420928D01*
Y1414251D01*
G03X129478Y1411143I1702J-1551D01*
G01Y1410675D01*
G02X129022Y1410279I-400J0D01*
G03X127224Y1406234I-322J-2279D01*
G01Y1256330D01*
G02X126541Y1256047I-400J0D01*
G01X125253Y1257335D01*
X125267Y1257435D01*
G03X122319Y1260383I-2575J373D01*
G01X122219Y1260369D01*
X121794Y1260794D01*
X121799Y1260882D01*
G03X119618Y1258701I-2299J118D01*
G01X119706Y1258706D01*
X120067Y1258344D01*
X119838Y1258116D01*
X119722Y1258154D01*
G03X119118Y1253669I-722J-2186D01*
G01X119206Y1253674D01*
X122524Y1250356D01*
Y1249743D01*
G03Y1245457I1476J-2143D01*
G01Y1096330D01*
G02X121841Y1096047I-400J0D01*
G01X89976Y1127912D01*
Y1145112D01*
X84976Y1150112D01*
Y1333312D01*
X43676Y1374612D01*
Y1411412D01*
X41722Y1413366D01*
Y1431743D01*
X30802Y1442664D01*
Y1490887D01*
X22822Y1498866D01*
Y1504918D01*
G02X23530Y1505173I400J0D01*
G03Y1515771I6391J5299D01*
G02X22822Y1516026I-308J255D01*
G01Y1633732D01*
X26428Y1637337D01*
Y1757139D01*
X26924Y1757636D01*
G02X27606Y1757381I283J-283D01*
G03X31556Y1761331I3693J257D01*
G02X31301Y1762013I28J399D01*
G01X37112Y1767824D01*
X38912D01*
X45094Y1774006D01*
X45182Y1774001D01*
G03X43001Y1776182I118J2299D01*
G01X43006Y1776094D01*
X42054Y1775143D01*
G02X41376Y1775369I-282J283D01*
G03X38431Y1772424I-2576J-369D01*
G02X38657Y1771746I-57J-396D01*
G01X37688Y1770776D01*
X35888D01*
X25359Y1760247D01*
G02X24676Y1760530I-283J283D01*
G01Y1761099D01*
G02X25065Y1761499I400J0D01*
G03X22701Y1763682I-65J2301D01*
G01X22706Y1763594D01*
X21724Y1762612D01*
Y1708671D01*
G02X21009Y1708423I-400J-1D01*
G03X18776Y1709263I-1810J-1423D01*
G02X18302Y1709656I-74J393D01*
G01Y1769023D01*
X38989Y1789709D01*
X39077Y1789706D01*
G03X36579Y1792204I102J2600D01*
G01X36582Y1792116D01*
X14900Y1770433D01*
Y1709141D01*
G02X14420Y1708750I-400J1D01*
G03Y1703650I-520J-2550D01*
G02X14900Y1703259I80J-392D01*
G01Y1692021D01*
G02X14322Y1691663I-400J0D01*
G03X11090Y1688954I-1022J-2063D01*
G01X11098Y1688927D01*
Y1651494D01*
G02X10669Y1651096I-400J1D01*
G03Y1646504I-169J-2296D01*
G02X11098Y1646106I29J-399D01*
G01Y1645212D01*
X9098Y1643212D01*
Y1492312D01*
X7020Y1490233D01*
Y1379867D01*
X61698Y1325188D01*
Y1167426D01*
X58298Y1164026D01*
Y1145326D01*
X38198Y1125226D01*
Y1109226D01*
X37036Y1108064D01*
G03Y1103536I2264J-2264D01*
G01X37765Y1102808D01*
G02X37485Y1102125I-283J-283D01*
G03X36024Y1098057I15J-2302D01*
G01Y1000143D01*
G03Y995857I1476J-2143D01*
G01Y993590D01*
G03X38024Y989018I1676J-1990D01*
G02X38474Y988621I50J-397D01*
G01Y933865D01*
G03Y929933I2526J-1966D01*
G01Y910047D01*
X46398Y902122D01*
Y882374D01*
X48798Y879974D01*
Y848674D01*
X53598Y843874D01*
Y828818D01*
G02X52903Y828549I-400J1D01*
G03X49498Y825449I-1702J-1550D01*
G01Y781405D01*
X38092Y769999D01*
Y753501D01*
X40698Y750895D01*
Y702395D01*
X43155Y699939D01*
G02X43113Y699337I-283J-283D01*
G03X42238Y697926I1387J-1837D01*
G01Y697925D01*
X42226Y697864D01*
X39748Y695386D01*
Y692887D01*
X9244Y662384D01*
X9243D01*
X7354Y660495D01*
Y470582D01*
X7352Y470580D01*
Y445995D01*
X7354Y445993D01*
Y317011D01*
X14224Y310142D01*
Y238746D01*
X28803Y224167D01*
G02X28791Y223589I-282J-283D01*
G03X31299Y217164I2508J-2723D01*
G01X31500D01*
Y214568D01*
X31299D01*
G03X31020Y207175I0J-3702D01*
G01X31094Y207169D01*
X31288Y206975D01*
X30948Y206636D01*
Y179666D01*
G03X34252Y176500I1477J-1766D01*
G01X36212D01*
X37006Y175706D01*
X37001Y175618D01*
G03X40657Y173641I2299J-118D01*
G02X41264Y173467I236J-323D01*
G03X43202Y172032I2136J858D01*
G01X43275Y172025D01*
X44098Y171202D01*
Y166495D01*
X46122Y164471D01*
Y79971D01*
X61480Y64613D01*
X61420Y64485D01*
G03X65250Y64995I2080J-985D01*
G01X65202Y65051D01*
Y65589D01*
G03X62338Y69146I-1203J1963D01*
G02X61766Y69140I-289J277D01*
G01X49526Y81381D01*
Y150559D01*
G02X49925Y150959I400J0D01*
G03X51616Y151700I-1J2302D01*
G01X54374D01*
Y103437D01*
X56188Y101624D01*
X56174Y101524D01*
G03X59122Y98576I2575J-373D01*
G01X59222Y98590D01*
X80024Y77788D01*
Y77269D01*
X79958Y77209D01*
G03X82457Y73406I1542J-1709D01*
G02X83024Y73043I167J-364D01*
G01Y68641D01*
X85959Y65706D01*
X85954Y65618D01*
G03X88135Y67799I2299J-118D01*
G01X88047Y67794D01*
X85976Y69865D01*
Y80612D01*
X80961Y85627D01*
X80975Y85727D01*
G03X77947Y88662I-2575J373D01*
G01X77844Y88644D01*
X59078Y107411D01*
Y184578D01*
X59900Y185400D01*
X62223D01*
G02X62545Y184763I0J-400D01*
G03X66166Y181924I1855J-1363D01*
G01X70984D01*
X77999Y174909D01*
X77857Y174767D01*
G03X79038Y168198I2852J-2878D01*
G02X79155Y167551I-166J-364D01*
G01X73824Y162219D01*
Y157066D01*
G03X76776I1476J-1766D01*
G01Y159180D01*
G02X77494Y159423I400J0D01*
G03X82218Y165649I3215J2466D01*
G02X82084Y166303I149J371D01*
G01X82569Y166788D01*
X82823D01*
X85876Y169841D01*
Y170095D01*
X86295Y170514D01*
G02X86949Y170380I283J-283D01*
G03X94693Y172627I3760J1510D01*
G02X95086Y173100I393J73D01*
G01X96332D01*
G02X96725Y172627I0J-400D01*
G03X104693I3984J-738D01*
G02X105086Y173100I393J73D01*
G01X106332D01*
G02X106725Y172627I0J-400D01*
G03X114036Y174203I3984J-738D01*
G01X113940Y174340D01*
X114123Y174524D01*
X115912D01*
X144321Y202932D01*
X145833D01*
G03X153633Y204856I3773J1478D01*
G02X154030Y205300I398J44D01*
G01X155182D01*
G02X155579Y204856I-1J-400D01*
G03X162649Y207084I4027J-447D01*
G01X162525Y207225D01*
X166790Y211490D01*
X166931Y211366D01*
G03X168690Y218356I2675J3043D01*
G02X168200Y218745I-90J390D01*
G01Y220073D01*
G02X168690Y220462I400J-1D01*
G03Y228356I916J3947D01*
G02X168200Y228745I-90J390D01*
G01Y230073D01*
G02X168690Y230462I400J-1D01*
G03X173369Y235913I916J3947D01*
G01X173320Y236035D01*
X175308Y238024D01*
X176526D01*
G02X176803Y237335I0J-400D01*
G03X182409I2803J-2926D01*
G02X182686Y238024I277J289D01*
G01X182812D01*
X199752Y254964D01*
Y407741D01*
X203009Y410998D01*
G02X203692Y410716I283J-283D01*
G01Y43307D01*
G02X202756Y42371I-936J0D01*
G01X72835D01*
G03X65897Y35433I0J-6938D01*
G01Y3937D01*
G02X64961Y3001I-936J0D01*
G01X3937D01*
G02X3001Y3937I0J936D01*
G01Y1328776D01*
G02X3731Y1329002I400J0D01*
G03Y1348164I13985J9581D01*
G02X3001Y1348390I-330J226D01*
G01Y1964567D01*
G37*
G36*
G01X30998Y362257D02*
X30824Y362234D01*
G03X28503Y360990I474J-3672D01*
G02X27802Y361252I-301J263D01*
G01Y365600D01*
X22822Y370579D01*
Y449124D01*
G02X23505Y449407I400J0D01*
G01X30998Y441913D01*
Y362257D01*
G37*
G36*
G01X33900Y443188D02*
X27857Y449231D01*
G02X28222Y449905I283J283D01*
G03X37409Y454447I1699J8126D01*
G02X38170Y454274I361J-173D01*
G01Y447458D01*
X33900Y443188D01*
G37*
G36*
G01X38170Y461788D02*
G02X37409Y461615I-400J0D01*
G03X26797Y465722I-7488J-3584D01*
G02X26364Y466376I-151J371D01*
G01X34276Y474288D01*
Y482944D01*
G02X34959Y483227I400J0D01*
G01X38170Y480016D01*
Y461788D01*
G37*
G36*
G01X23530Y539347D02*
G03X32603Y536790I6390J5299D01*
G02X33015Y536128I129J-379D01*
G01X26237Y529351D01*
X22822Y532766D01*
Y539092D01*
G02X23530Y539347I400J0D01*
G37*
G36*
G01X34813Y576725D02*
X37116Y579028D01*
G02X37798Y578745I282J-283D01*
G01Y549096D01*
G02X37055Y548891I-400J0D01*
G03X23530Y549945I-7134J-4245D01*
G02X22822Y550200I-308J255D01*
G01Y557734D01*
X32976Y567888D01*
Y571599D01*
G02X33387Y571999I400J0D01*
G03X34853Y576125I63J2301D01*
G02X34813Y576725I243J318D01*
G37*
G36*
G01X12740Y568869D02*
G02X12057Y569152I-283J283D01*
G01Y621375D01*
G02X12806Y621572I400J1D01*
G03X44108Y626247I14753J8349D01*
G02X44898Y626160I390J-87D01*
G01Y598305D01*
X38622Y592029D01*
X38517Y592050D01*
G03X35551Y588620I-517J-2550D01*
G01X35594Y588501D01*
X25907Y578813D01*
G02X25302Y578858I-283J283D01*
G03X21151Y577373I-1852J-1367D01*
G01X21156Y577285D01*
X18508Y574637D01*
X18408Y574651D01*
G03X15460Y571703I-373J-2575D01*
G01X15474Y571603D01*
X12740Y568869D01*
G37*
G36*
G01X44108Y633595D02*
G03X12806Y638270I-16549J-3674D01*
G02X12057Y638467I-349J196D01*
G01Y658545D01*
X44216Y690704D01*
G02X44899Y690421I283J-283D01*
G01Y677735D01*
G02X44336Y677369I-400J0D01*
G03X41434Y676824I-1056J-2378D01*
G02X40877Y676814I-284J282D01*
G03X40943Y673084I-1781J-1897D01*
G02X41500Y673094I284J-282D01*
G03X44336Y672613I1781J1897D01*
G02X44898Y672247I162J-366D01*
G01Y633682D01*
G02X44108Y633595I-400J0D01*
G37*
G36*
G01X23530Y1418559D02*
G03X36312I6391J5299D01*
G02X37020Y1418304I308J-255D01*
G01Y1412508D01*
X35224Y1410712D01*
Y1378330D01*
G02X34541Y1378047I-400J0D01*
G01X22822Y1389766D01*
Y1418304D01*
G02X23530Y1418559I400J0D01*
G37*
G36*
G01X11423Y1455571D02*
Y1488409D01*
X11993Y1488980D01*
X12227Y1488746D01*
X12179Y1488624D01*
G03X19041Y1484678I3727J-1459D01*
G02X19754Y1484429I313J-249D01*
G01Y1479901D01*
G02X19041Y1479652I-400J0D01*
G03Y1474678I-3135J-2487D01*
G02X19754Y1474429I313J-249D01*
G01Y1469901D01*
G02X19041Y1469652I-400J0D01*
G03X17372Y1463441I-3135J-2487D01*
G01X17494Y1463489D01*
X18004Y1462978D01*
Y1461226D01*
G02X17450Y1460857I-400J0D01*
G03X12102Y1455922I-1544J-3692D01*
G01X12140Y1455805D01*
X11764Y1455429D01*
G02X11423Y1455571I-141J142D01*
G37*
G36*
G01X94224Y241276D02*
G02X93908Y241922I0J400D01*
G03X86949Y245918I-3198J2487D01*
G02X86295Y245784I-371J149D01*
G01X85810Y246269D01*
Y246523D01*
X82823Y249510D01*
X78595D01*
X78586Y249502D01*
X73298D01*
X72840Y249960D01*
X72860Y250064D01*
G03X72302Y252051I-2260J437D01*
G01Y266812D01*
X70033Y269081D01*
X70019Y269106D01*
G03X67807Y270294I-2019J-1106D01*
G01X67714Y270286D01*
X62586Y275414D01*
X62594Y275507D01*
G03X61776Y277466I-2294J192D01*
G01Y288912D01*
X56026Y294662D01*
Y368387D01*
X54226Y370187D01*
Y432938D01*
X59906Y438618D01*
X59950Y438633D01*
G03X59450Y443673I-846J2461D01*
G01X59276Y443696D01*
Y478288D01*
X68276Y487288D01*
Y537088D01*
X74916Y543728D01*
G02X75598Y543445I282J-283D01*
G01Y540973D01*
X75590Y540946D01*
G03Y539654I2210J-646D01*
G01X75598Y539627D01*
Y531315D01*
X75640Y531273D01*
Y530693D01*
X72798Y527851D01*
Y524787D01*
G02X72359Y524389I-400J0D01*
G03Y519211I-259J-2589D01*
G02X72798Y518813I39J-398D01*
G01Y517775D01*
G02X72345Y517379I-400J0D01*
G03Y512221I-345J-2579D01*
G02X72798Y511825I53J-396D01*
G01Y509842D01*
G02X72319Y509450I-400J0D01*
G03Y504350I-519J-2550D01*
G02X72798Y503958I79J-392D01*
G01Y503514D01*
X72573D01*
X72549Y503520D01*
G03X72332Y498434I-649J-2520D01*
G02X72798Y498040I66J-394D01*
G01Y447356D01*
X62521Y437078D01*
X62467Y437065D01*
G03X65388Y433308I629J-2525D01*
G02X66108Y433276I352J-189D01*
G03X69279Y436783I2392J1024D01*
G02X69116Y437447I120J381D01*
G01X77202Y445532D01*
Y478758D01*
G02X77681Y479150I400J0D01*
G03X80669Y480879I519J2550D01*
G02X81175Y481132I379J-126D01*
G03X84201Y484987I825J2468D01*
G01Y489536D01*
X95202Y500536D01*
Y527411D01*
X93334Y529278D01*
X93320Y529304D01*
G03X89671Y529827I-2020J-1104D01*
G02X89138Y529797I-283J282D01*
G03X85490Y527354I-1438J-1797D01*
G01X85498Y527327D01*
Y526361D01*
X87598Y524261D01*
Y508444D01*
G02X86906Y508172I-400J0D01*
G03Y504628I-1906J-1772D01*
G02X87598Y504356I292J-272D01*
G01Y503686D01*
X77884Y493972D01*
G02X77202Y494255I-282J283D01*
G01Y498058D01*
G02X77681Y498450I400J0D01*
G03Y503550I519J2550D01*
G02X77202Y503942I-79J392D01*
G01Y504122D01*
G02X77480Y504306I200J0D01*
G03X77721Y509183I1020J2394D01*
G02X77202Y509564I-119J381D01*
G01Y511825D01*
G02X77655Y512221I400J0D01*
G03Y517379I345J2579D01*
G02X77202Y517775I-53J396D01*
G01Y519396D01*
G02X77841Y519717I400J1D01*
G03Y523883I1559J2083D01*
G02X77202Y524204I-239J320D01*
G01Y526027D01*
X80044Y528869D01*
Y533097D01*
X80002Y533139D01*
Y539627D01*
X80010Y539654D01*
G03Y540946I-2210J646D01*
G01X80002Y540973D01*
Y542588D01*
X113413Y576000D01*
X119665D01*
G02X120055Y575511I0J-400D01*
G03X122482Y572705I2245J-511D01*
G01X122574Y572713D01*
X125698Y569588D01*
Y545779D01*
G02X125016Y545496I-400J0D01*
G01X117236Y553276D01*
X117068D01*
X117009Y553342D01*
G03X113038Y552229I-1709J-1542D01*
G02X112313Y552081I-393J74D01*
G03X108381Y551906I-1913J-1281D01*
G01X108367Y551881D01*
X103098Y546612D01*
Y526587D01*
G03X102775Y525829I2202J-1386D01*
G01X102762Y525775D01*
X101324Y524337D01*
Y521956D01*
G02X100800Y521576I-400J0D01*
G03Y516624I-800J-2476D01*
G02X101324Y516244I124J-380D01*
G01Y514856D01*
G02X100800Y514476I-400J0D01*
G03Y509524I-800J-2476D01*
G02X101324Y509144I124J-380D01*
G01Y508856D01*
G02X100800Y508476I-400J0D01*
G03Y503524I-800J-2476D01*
G02X101324Y503144I124J-380D01*
G01Y502856D01*
G02X100800Y502476I-400J0D01*
G03Y497524I-800J-2476D01*
G02X101324Y497144I124J-380D01*
G01Y496856D01*
G02X100800Y496476I-400J0D01*
G03Y491524I-800J-2476D01*
G02X101324Y491144I124J-380D01*
G01Y490856D01*
G02X100800Y490476I-400J0D01*
G03Y485524I-800J-2476D01*
G02X101324Y485144I124J-380D01*
G01Y484784D01*
G02X100774Y484413I-400J0D01*
G03Y479587I-974J-2413D01*
G02X101324Y479216I150J-371D01*
G01Y475643D01*
G02X100734Y475291I-400J0D01*
G03Y470709I-1234J-2291D01*
G02X101324Y470357I190J-352D01*
G01Y453963D01*
X116488Y438798D01*
X116702D01*
G02X116844Y438457I0J-200D01*
G01X110588Y432202D01*
X87475D01*
G02X87079Y432655I0J400D01*
G03X81921I-2579J345D01*
G02X81525Y432202I-396J-53D01*
G01X77588D01*
X76919Y431533D01*
X76894Y431519D01*
G03X79551Y427798I1107J-2019D01*
G01X85636D01*
G02X86017Y427279I0J-400D01*
G03X90983I2483J-779D01*
G02X91364Y427798I381J119D01*
G01X112412D01*
X123581Y438967D01*
X123606Y438981D01*
G03X121854Y443210I-1105J2020D01*
G01X121827Y443202D01*
X118312D01*
X105726Y455787D01*
Y522513D01*
X105875Y522662D01*
X105929Y522675D01*
G03X107502Y526587I-629J2525D01*
G01Y544788D01*
X111481Y548767D01*
X111506Y548781D01*
G03X112662Y550371I-1106J2019D01*
G02X113387Y550519I393J-74D01*
G03X116373Y549764I1912J1281D01*
G01X116504Y549832D01*
X144698Y521637D01*
Y520487D01*
G02X144259Y520089I-400J0D01*
G03Y514911I-259J-2589D01*
G02X144698Y514513I39J-398D01*
G01Y512185D01*
G02X144254Y511788I-400J0D01*
G03Y507212I-254J-2288D01*
G02X144698Y506815I44J-397D01*
G01Y504487D01*
G02X144259Y504089I-400J0D01*
G03Y498911I-259J-2589D01*
G02X144698Y498513I39J-398D01*
G01Y496487D01*
G02X144259Y496089I-400J0D01*
G03Y490911I-259J-2589D01*
G02X144698Y490513I39J-398D01*
G01Y489169D01*
G02X144259Y488771I-400J0D01*
G03Y483593I-259J-2589D01*
G02X144698Y483195I39J-398D01*
G01Y454711D01*
X138606Y448618D01*
G02X138014Y448648I-282J283D01*
G03X133833Y448440I-2014J-1648D01*
G02X133167I-333J222D01*
G03Y445560I-2167J-1440D01*
G02X133833I333J-222D01*
G03X133996Y445341I2166J1442D01*
G01X134112Y445201D01*
X125724Y436813D01*
Y247766D01*
G03X128676I1476J-1766D01*
G01Y429144D01*
G02X129200Y429524I400J0D01*
G03Y434476I800J2476D01*
G02X128676Y434856I-124J380D01*
G01Y435589D01*
X132931Y439843D01*
G02X133552Y439774I283J-283D01*
G03X135524Y438698I1948J1226D01*
G01Y426988D01*
X139924Y422588D01*
Y384212D01*
X134324Y378612D01*
Y246812D01*
X130788Y243276D01*
X120612D01*
X113312Y250576D01*
X104788D01*
X102335Y248123D01*
X102212Y248172D01*
G03X97510Y241922I-1503J-3763D01*
G02X97194Y241276I-316J-246D01*
G01X94224D01*
G37*
G36*
G01X54123Y510940D02*
Y504811D01*
G02X53371Y504622I-400J0D01*
G03X42168Y506088I-6127J-3284D01*
G02X41476Y506361I-292J273D01*
G01Y522569D01*
X53441Y534534D01*
G02X54123Y534251I282J-283D01*
G01Y524717D01*
G02X53454Y524422I-400J1D01*
G03Y520578I-1754J-1922D01*
G02X54124Y520283I270J-295D01*
G01Y515260D01*
G02X53483Y514940I-400J0D01*
G03Y511260I-1383J-1840D01*
G02X54123Y510940I240J-320D01*
G37*
G36*
G01X62327Y545180D02*
Y553938D01*
X83576Y575188D01*
Y582836D01*
X88716Y587976D01*
G02X89398Y587693I282J-283D01*
G01Y581687D01*
X85524Y577812D01*
Y567412D01*
X63009Y544897D01*
G02X62327Y545180I-282J283D01*
G37*
G36*
G01X55202Y676447D02*
X56622Y677868D01*
X56705D01*
G03X58411Y678357I5J3201D01*
G02X59024Y678018I213J-339D01*
G01Y676843D01*
G03Y672557I1476J-2143D01*
G01Y671535D01*
X58989Y671484D01*
G03X62074Y672180I1911J-1284D01*
G01X61976Y672238D01*
Y672555D01*
X62057Y672615D01*
G03X61976Y676843I-1557J2085D01*
G01Y679407D01*
G02X62659Y679689I400J-1D01*
G01X65824Y676525D01*
Y664070D01*
X67003Y662890D01*
X67000Y662803D01*
G03X67898Y660731I2600J-104D01*
G01Y619205D01*
X62298Y613605D01*
Y599205D01*
X55884Y592791D01*
G02X55202Y593073I-282J283D01*
G01Y672827D01*
X55210Y672854D01*
G03Y674146I-2210J646D01*
G01X55202Y674173D01*
Y676447D01*
G37*
G36*
G01X60576Y557330D02*
Y559812D01*
X73452Y572687D01*
Y574011D01*
X79941Y580501D01*
G02X80624Y580218I283J-283D01*
G01Y576412D01*
X61259Y557047D01*
G02X60576Y557330I-283J283D01*
G37*
G36*
G01X67876Y572254D02*
Y575688D01*
X78141Y585953D01*
G02X78824Y585670I283J-283D01*
G01Y583560D01*
X70498Y575235D01*
Y573911D01*
X68559Y571971D01*
G02X67876Y572254I-283J283D01*
G37*
G36*
G01X55324Y579093D02*
G03X56795Y574348I1476J-2143D01*
G02X57077Y573665I-1J-400D01*
G01X49009Y565597D01*
G02X48326Y565880I-283J283D01*
G01Y574538D01*
X54641Y580853D01*
G02X55324Y580570I283J-283D01*
G01Y579093D01*
G37*
G36*
G01X81776Y586178D02*
Y587088D01*
X85576Y590888D01*
Y592070D01*
G02X86259Y592353I400J0D01*
G01X87398Y591213D01*
Y590835D01*
X82459Y585895D01*
G02X81776Y586178I-283J283D01*
G37*
G36*
G01X91372Y670288D02*
X97901Y663760D01*
X97908Y663688D01*
G03X100561Y661626I2292J212D01*
G02X101024Y661231I63J-395D01*
G01Y659602D01*
G02X100620Y659202I-400J0D01*
G03X99124Y654457I-20J-2602D01*
G01Y644712D01*
X73934Y619522D01*
G02X73252Y619805I-282J283D01*
G01Y664117D01*
G02X73934Y664400I400J0D01*
G01X80061Y658272D01*
X81757D01*
G03X86043I2143J1477D01*
G01X86824D01*
G03X91462Y660489I2143J1476D01*
G02X91689Y660971I383J114D01*
G03X92150Y665510I-1015J2396D01*
G01Y666338D01*
X86071Y672417D01*
X86163Y672553D01*
G03X85636Y676023I-2163J1447D01*
G02X85586Y676597I251J311D01*
G03X86138Y678358I-1736J1511D01*
G02X86545Y678802I398J44D01*
G03X86715Y678804I58J2301D01*
G01X86803Y678809D01*
X91372Y674239D01*
Y670288D01*
G37*
G36*
G01X73425Y725737D02*
X73483Y725749D01*
G03X73643Y725790I-491J2249D01*
G01X73670Y725797D01*
X73898D01*
Y700515D01*
X69084Y695700D01*
G02X68402Y695983I-282J283D01*
G01Y720713D01*
X73425Y725737D01*
G37*
G36*
G01X102759Y645747D02*
G02X102076Y646030I-283J283D01*
G01Y654457D01*
G03X103175Y656973I-1476J2143D01*
G01X103161Y657073D01*
X103976Y657888D01*
Y669312D01*
X103161Y670127D01*
X103175Y670227D01*
G03X100620Y667998I-2575J373D01*
G02X101024Y667598I4J-400D01*
G01Y666569D01*
G02X100561Y666174I-400J0D01*
G03X99793Y666166I-360J-2274D01*
G01X99690Y666147D01*
X94326Y671512D01*
Y675463D01*
X88891Y680897D01*
X88896Y680985D01*
G03X88074Y682869I-2299J118D01*
G01Y688907D01*
X84402Y692579D01*
Y721399D01*
G02X85053Y721710I400J0D01*
G03X88202Y725051I1448J1790D01*
G01Y794295D01*
X105573Y811666D01*
X105660Y811663D01*
G03X108363Y814366I103J2600D01*
G01X108360Y814453D01*
X108941Y815034D01*
G02X109623Y814752I282J-283D01*
G01Y804417D01*
G02X108927Y804148I-400J0D01*
G03X105141Y800580I-1927J-1748D01*
G02Y800020I-286J-280D01*
G03X105010Y796524I1859J-1820D01*
G02X104994Y795991I-306J-258D01*
G03X108912Y792573I1888J-1791D01*
G02X109623Y792322I311J-251D01*
G01Y790343D01*
G03X109624Y786057I1477J-2143D01*
G01Y783812D01*
X106398Y780587D01*
Y737712D01*
X106396Y737710D01*
Y709167D01*
X106398Y709165D01*
Y708835D01*
X106396Y708833D01*
Y698588D01*
X104846Y697038D01*
Y678565D01*
X107812Y675600D01*
Y673711D01*
X107810Y673710D01*
Y667858D01*
G03X110546Y664180I1195J-1967D01*
G02X111096Y664165I267J-297D01*
G01X111706Y663556D01*
X111701Y663468D01*
G03X114118Y661051I2299J-118D01*
G01X114206Y661056D01*
X115987Y659274D01*
X117439D01*
X120871Y655843D01*
G02X120872Y655277I-282J-283D01*
G03X120201Y653532I1628J-1627D01*
G01X120206Y653444D01*
X119883Y653121D01*
X119693Y653312D01*
X119685Y653380D01*
G03X115721Y654675I-2285J-280D01*
G02X115079Y654756I-292J274D01*
G03X111408Y655699I-2279J-1256D01*
G02X110796Y656008I-213J338D01*
G03X106724Y653682I-2596J-183D01*
G01Y651301D01*
G02X106334Y650901I-400J0D01*
G03X104037Y647210I66J-2601D01*
G01X104096Y647084D01*
X102759Y645747D01*
G37*
G36*
G01X52484Y679957D02*
G02X51802Y680240I-282J283D01*
G01Y703287D01*
X51794Y703294D01*
X51799Y703382D01*
G03X49173Y705779I-2299J118D01*
G02X48729Y706075I-57J396D01*
G03X44797Y707049I-2229J-575D01*
G02X44102Y707318I-295J270D01*
G01Y752305D01*
X41496Y754911D01*
Y756137D01*
G02X42186Y756412I400J0D01*
G03X52875Y757104I5058J4769D01*
G02X53598Y756870I323J-235D01*
G01Y697197D01*
X54482Y696313D01*
Y693210D01*
X53508Y692236D01*
Y681069D01*
G03X53509Y681064I3079J613D01*
G01Y680981D01*
X52484Y679957D01*
G37*
G36*
G01X70284Y728711D02*
G03X67721Y724886I-1284J-1911D01*
G02X67782Y724270I-222J-333D01*
G01X66884Y723372D01*
G02X66202Y723655I-282J283D01*
G01Y759595D01*
G02X66884Y759878I400J0D01*
G01X73898Y752863D01*
Y730656D01*
G02X73425Y730262I-400J-1D01*
G03X70876Y728888I-425J-2262D01*
G02X70284Y728711I-369J155D01*
G37*
G36*
G01X127124Y665430D02*
G02X126441Y665147I-400J0D01*
G01X125152Y666437D01*
Y688486D01*
X123263Y690374D01*
X123277Y690474D01*
G03X118352Y689729I-2575J373D01*
G02X118202Y689218I-361J-172D01*
G03X117001Y686635I1374J-2210D01*
G01X117015Y686535D01*
X115348Y684869D01*
Y668749D01*
G02X115007Y668608I-200J0D01*
G01X114676Y668939D01*
Y699712D01*
X113102Y701287D01*
Y761313D01*
X114744Y762956D01*
X114844Y762942D01*
G03X117792Y765890I373J2575D01*
G01X117778Y765990D01*
X128152Y776363D01*
Y852189D01*
X114789Y865552D01*
X108342D01*
X107370Y864579D01*
X107282Y864584D01*
G03X105398Y863762I-118J-2299D01*
G01X104585D01*
X104551Y863920D01*
G03X100597Y864987I-2251J-482D01*
G02X99901Y865256I-296J269D01*
G01Y870513D01*
X101294Y871906D01*
X101382Y871901D01*
G03X99201Y874082I118J2299D01*
G01X99206Y873994D01*
X96948Y871737D01*
Y834863D01*
X97424Y834388D01*
Y824666D01*
G03X100376I1476J-1766D01*
G01Y835612D01*
X99902Y836087D01*
Y838298D01*
G02X100301Y838698I400J0D01*
G03X102066Y839524I-1J2302D01*
G01X104425D01*
G03X107721Y838812I1979J1176D01*
G01X107858Y838908D01*
X115398Y831367D01*
Y826800D01*
G02X114984Y826400I-400J0D01*
G03X112639Y823669I-84J-2300D01*
G01X112659Y823565D01*
X105953Y816860D01*
X105866Y816863D01*
G03X103163Y814160I-103J-2600D01*
G01X103166Y814073D01*
X84798Y795705D01*
Y756680D01*
G02X84116Y756397I-400J0D01*
G01X73876Y766637D01*
Y821134D01*
G03X74008Y824547I-1476J1766D01*
G02X74004Y825116I279J286D01*
G01X74152Y825263D01*
Y1128729D01*
X69863Y1133017D01*
X69877Y1133117D01*
G03X67675Y1130915I-2575J373D01*
G01X67775Y1130929D01*
X71198Y1127505D01*
Y906155D01*
G02X70516Y905872I-400J0D01*
G01X69561Y906827D01*
X69575Y906927D01*
G03X68476Y909443I-2575J373D01*
G01Y1013764D01*
X55278Y1026962D01*
X55273Y1026969D01*
G03X54467Y1023411I-1773J-1469D01*
G01X54594Y1023470D01*
X65524Y1012540D01*
Y983284D01*
G02X64974Y982913I-400J0D01*
G03Y978087I-974J-2413D01*
G02X65524Y977716I150J-371D01*
G01Y918430D01*
G02X64841Y918147I-400J0D01*
G01X56761Y926227D01*
X56775Y926327D01*
G03X54642Y929264I-2575J373D01*
G01X54476Y929293D01*
Y994243D01*
X54622Y994284D01*
G03X53256Y998678I-622J2216D01*
G02X52726Y999057I-130J379D01*
G01Y1016477D01*
G03X50916Y1020300I-1726J1523D01*
G02X50502Y1020700I-14J400D01*
G01Y1121195D01*
X56737Y1127430D01*
X56824Y1127427D01*
G03X59527Y1130130I103J2600D01*
G01X59524Y1130217D01*
X72208Y1142901D01*
G02X72890Y1142619I282J-283D01*
G01Y1142021D01*
X79024Y1135888D01*
Y1124388D01*
X121424Y1081988D01*
Y1009543D01*
G03X121343Y1005315I1476J-2143D01*
G01X121424Y1005255D01*
Y1004948D01*
X139648Y986723D01*
Y951643D01*
X141611Y949680D01*
X145239D01*
X146294Y950736D01*
X146382Y950731D01*
G03X148533Y951950I118J2299D01*
G02X148794Y952037I176J-94D01*
G03X150323Y951886I978J2084D01*
G02X150560Y951754I47J-194D01*
G03X151054Y950914I2187J721D01*
G01X151185Y950773D01*
X146148Y945737D01*
Y902364D01*
G03X147499Y898198I1352J-1864D01*
G02X147898Y897798I-1J-400D01*
G01Y847487D01*
X132098Y831687D01*
Y683507D01*
X127124Y678532D01*
Y671643D01*
G03Y667357I1476J-2143D01*
G01Y665430D01*
G37*
G36*
G01X66775Y886538D02*
G03X67284Y886500I425J2262D01*
G02X67698Y886100I14J-400D01*
G01Y829087D01*
X66884Y828272D01*
G02X66202Y828555I-282J283D01*
G01Y843887D01*
X59540Y850548D01*
X59677Y850689D01*
G03X59286Y854643I-1868J1812D01*
G01Y881251D01*
X57476Y883060D01*
Y883734D01*
G03X53729Y885124I-1476J1766D01*
G02X53051Y884776I-395J-65D01*
G01X52802Y885026D01*
Y902227D01*
G02X53484Y902509I400J-1D01*
G01X59198Y896795D01*
Y894969D01*
G03X59898Y890598I1702J-1969D01*
G01Y886751D01*
G03X61859Y882913I1702J-1551D01*
G02X62303Y882543I45J-397D01*
G03X66302Y884251I2297J158D01*
G01Y886144D01*
G02X66775Y886538I400J1D01*
G37*
G36*
G01X56798Y914469D02*
G03Y910531I1702J-1969D01*
G01Y908573D01*
G02X56116Y908291I-400J1D01*
G01X50502Y913905D01*
Y921127D01*
G02X51184Y921409I400J-1D01*
G01X56798Y915795D01*
Y914469D01*
G37*
G36*
G01X78765Y1145480D02*
X83024Y1141221D01*
Y1140110D01*
G02X82341Y1139827I-400J0D01*
G01X77594Y1144575D01*
Y1145054D01*
G02X78033Y1145452I400J0D01*
G03X78665Y1145466I259J2589D01*
G01X78765Y1145480D01*
G37*
G36*
G01X64701Y1161374D02*
X66016Y1162688D01*
G02X66698Y1162405I282J-283D01*
G01Y1145605D01*
X65384Y1144291D01*
G02X64701Y1144573I-283J283D01*
G01Y1161374D01*
G37*
G36*
G01X40041Y1375047D02*
X38176Y1376912D01*
Y1409488D01*
X39800Y1411112D01*
X40724Y1410188D01*
Y1375330D01*
G02X40041Y1375047I-400J0D01*
G37*
G36*
G01X140188Y241000D02*
X139912Y241276D01*
X139270D01*
G02X138870Y241677I0J400D01*
G03X138753Y241959I-400J-1D01*
G01X136200Y244512D01*
X137276Y245588D01*
Y377388D01*
X142876Y382988D01*
Y423812D01*
X138476Y428212D01*
Y437188D01*
X152676Y451388D01*
Y554112D01*
X149076Y557712D01*
Y561169D01*
G02X149759Y561452I400J0D01*
G01X166527Y544684D01*
G02X166244Y544002I-283J-282D01*
G01X160523D01*
X160496Y544010D01*
G03Y539590I-646J-2210D01*
G01X160523Y539598D01*
X166588D01*
X176762Y529425D01*
X176775Y529371D01*
G03X177224Y528432I2524J630D01*
G01Y525605D01*
G02X176567Y525298I-400J0D01*
G03Y521302I-1667J-1998D01*
G02X177224Y520995I257J-307D01*
G01Y449413D01*
X188752Y437884D01*
G02X188469Y437202I-283J-282D01*
G01X148648D01*
X145879Y434433D01*
X145854Y434419D01*
G03X144898Y433423I1106J-2019D01*
G02X144201Y433388I-358J178D01*
G03X144395Y430983I-2201J-1388D01*
G02X145088Y431060I368J-156D01*
G03X148992Y431319I1872J1340D01*
G01X150472Y432798D01*
X159025D01*
G02X159421Y432345I0J-400D01*
G03X164579I2579J-345D01*
G02X164975Y432798I396J53D01*
G01X171525D01*
G02X171921Y432345I0J-400D01*
G03X177079I2579J-345D01*
G02X177475Y432798I396J53D01*
G01X188420D01*
X188898Y432320D01*
Y431793D01*
X189367Y431324D01*
X189381Y431299D01*
G03X192357Y430311I2019J1106D01*
G02X192924Y429948I167J-364D01*
G01Y426712D01*
X188324Y422112D01*
Y390488D01*
X190824Y387988D01*
Y274312D01*
X184214Y267702D01*
G02X183542Y267890I-283J283D01*
G03X176418Y264427I-3936J-961D01*
G02X176104Y263780I-315J-247D01*
G01X173108D01*
G02X172794Y264427I1J400D01*
G03X167377Y263545I-3188J2502D01*
G02X167440Y262928I-220J-334D01*
G01X163607Y259095D01*
G02X162990Y259158I-283J283D01*
G03X161715Y253469I-3384J-2229D01*
G02X162324Y253128I209J-341D01*
G01Y248210D01*
G02X161715Y247869I-400J0D01*
G03X156620Y241670I-2109J-3460D01*
G02X156325Y241000I-295J-270D01*
G01X152887D01*
G02X152592Y241670I0J400D01*
G03X146620I-2986J2739D01*
G02X146325Y241000I-295J-270D01*
G01X140188D01*
G37*
G36*
G01X112273Y581085D02*
X126687Y595499D01*
G02X127271Y595481I284J-282D01*
G03X130766Y595524I1729J1519D01*
G01X134357D01*
G03X138643I2143J1476D01*
G01X145212D01*
X148862Y599174D01*
X155162D01*
X171826Y615837D01*
Y617806D01*
G03X168872I-1477J2143D01*
G01Y617061D01*
X153938Y602126D01*
X149756D01*
G02X149473Y602809I0J400D01*
G01X160200Y613536D01*
Y625925D01*
X154826Y631299D01*
Y660435D01*
X153993Y661268D01*
X154007Y661368D01*
G03X152908Y663884I-2575J373D01*
G01Y666657D01*
X161002Y674750D01*
Y683487D01*
X160926Y683562D01*
Y688320D01*
G02X161609Y688603I400J0D01*
G01X168324Y681888D01*
Y627188D01*
X176498Y619013D01*
Y615887D01*
X150213Y589601D01*
G02X149629Y589619I-284J282D01*
G03X146123Y586636I-1729J-1520D01*
G01Y556488D01*
X149724Y552888D01*
Y526477D01*
G02X149041Y526194I-400J0D01*
G01X134533Y540702D01*
X134519Y540727D01*
G03X133581Y541653I-2018J-1107D01*
G01X130102Y545133D01*
Y571412D01*
X126197Y575317D01*
G02X126480Y576000I283J283D01*
G01X127513D01*
X129981Y578467D01*
X130006Y578481D01*
G03X126881Y581606I-1106J2019D01*
G01X126867Y581581D01*
X125689Y580403D01*
X112556D01*
G02X112273Y581085I0J400D01*
G37*
G36*
G01X145559Y604698D02*
X156565Y615705D01*
G02X157248Y615422I283J-283D01*
G01Y614760D01*
X143414Y600926D01*
X130180D01*
G02X129897Y601609I0J400D01*
G01X132987Y604698D01*
X145559D01*
G37*
G36*
G01X88476Y566076D02*
Y576588D01*
X92352Y580463D01*
Y596389D01*
X89932Y598809D01*
Y599033D01*
G02X90371Y599431I400J0D01*
G03X91003Y599445I259J2589D01*
G01X91103Y599459D01*
X97013Y593548D01*
X116595D01*
G02X116924Y592921I0J-400D01*
G01Y592812D01*
X90188Y566076D01*
X88476D01*
G37*
G36*
G01X134814Y664274D02*
X134202Y664887D01*
Y669113D01*
X134814Y669726D01*
G02X135496Y669443I282J-283D01*
G01Y664557D01*
G02X134814Y664274I-400J0D01*
G37*
G36*
G01X136023Y679213D02*
Y675112D01*
X133053Y672141D01*
G02X132370Y672424I-283J283D01*
G01Y675759D01*
X132538Y675786D01*
G03X134685Y678726I-428J2567D01*
G01X134671Y678826D01*
X135341Y679496D01*
G02X136023Y679213I282J-283D01*
G37*
G36*
G01X118711Y684055D02*
X118920Y683847D01*
X118910Y683753D01*
G03X120024Y681357I2590J-253D01*
G01Y667530D01*
G02X119341Y667247I-400J0D01*
G01X118302Y668287D01*
Y683645D01*
X118711Y684055D01*
G37*
G36*
G01X109241Y678347D02*
X107800Y679789D01*
Y695814D01*
X109350Y697364D01*
Y697880D01*
G02X109691Y698021I200J0D01*
G01X109924Y697788D01*
Y678630D01*
G02X109241Y678347I-400J0D01*
G37*
G36*
G01X125198Y777587D02*
X115690Y768078D01*
X115590Y768092D01*
G03X112642Y765144I-373J-2575D01*
G01X112656Y765044D01*
X112034Y764422D01*
G02X111352Y764705I-282J283D01*
G01Y772263D01*
X115929Y776841D01*
X116029Y776827D01*
G03X118977Y779775I373J2575D01*
G01X118963Y779875D01*
X120102Y781013D01*
Y836687D01*
X112976Y843812D01*
Y849834D01*
G03Y853366I-1476J1766D01*
G01Y859688D01*
X113194Y859906D01*
X113282Y859901D01*
G03X115027Y860572I118J2299D01*
G02X115593Y860571I283J-283D01*
G01X125198Y850965D01*
Y777587D01*
G37*
G36*
G01X117148Y782237D02*
X116875Y781963D01*
X116775Y781977D01*
G03X113827Y779029I-373J-2575D01*
G01X113841Y778929D01*
X110034Y775122D01*
G02X109351Y775405I-283J283D01*
G01Y779363D01*
X112576Y782588D01*
Y786057D01*
G03Y790343I-1476J2143D01*
G01Y816188D01*
X116466Y820078D01*
G02X117148Y819795I282J-283D01*
G01Y782237D01*
G37*
G36*
G01X175302Y630215D02*
Y691512D01*
X164702Y702112D01*
Y734312D01*
X160802Y738212D01*
Y751927D01*
X160810Y751954D01*
G03Y753246I-2210J646D01*
G01X160802Y753273D01*
Y825788D01*
X178876Y843863D01*
Y986470D01*
G02X179559Y986753I400J0D01*
G01X182698Y983613D01*
Y950187D01*
X180848Y948337D01*
Y776513D01*
X166648Y762313D01*
Y729789D01*
X170824Y725614D01*
Y696988D01*
X179624Y688188D01*
Y643788D01*
X182324Y641088D01*
Y618912D01*
X180134Y616722D01*
G02X179452Y617005I-282J283D01*
G01Y620237D01*
X174427Y625261D01*
G02X174634Y625936I283J282D01*
G03X175302Y630215I-438J2260D01*
G37*
G36*
G01X163612Y690776D02*
X163657Y690896D01*
G03X161565Y694001I-2157J804D01*
G02X161176Y694401I11J400D01*
G01Y698444D01*
G02X161859Y698727I400J0D01*
G01X170898Y689688D01*
Y684455D01*
G02X170216Y684172I-400J0D01*
G01X163612Y690776D01*
G37*
G36*
G01X148688Y688024D02*
X148681Y687933D01*
G03X149524Y685991I2297J-157D01*
G01Y674393D01*
X147884Y672753D01*
G02X147202Y673036I-282J283D01*
G01Y685912D01*
X145196Y687918D01*
Y828087D01*
X146491Y829383D01*
G02X147174Y829100I283J-283D01*
G01Y733638D01*
X147402Y733409D01*
Y699491D01*
X147348Y699437D01*
Y689363D01*
X148688Y688024D01*
G37*
G36*
G01X157024Y900171D02*
X156902Y900119D01*
G03X158331Y895760I899J-2119D01*
G02X158824Y895371I93J-389D01*
G01Y853412D01*
X153484Y848072D01*
G02X152801Y848355I-283J283D01*
G01Y941290D01*
X156341Y944830D01*
G02X157024Y944547I283J-283D01*
G01Y900171D01*
G37*
G36*
G01X162988Y986224D02*
X164324Y984888D01*
Y971230D01*
G02X163641Y970947I-400J0D01*
G01X162376Y972212D01*
Y985212D01*
X162047Y985541D01*
G02X162330Y986224I283J283D01*
G01X162988D01*
G37*
G36*
G01X143609Y1015703D02*
X164128Y995184D01*
G02X163845Y994501I-283J-283D01*
G01X162405D01*
X142926Y1013980D01*
Y1015420D01*
G02X143609Y1015703I400J0D01*
G37*
G36*
G01X192616Y390372D02*
X191276Y391712D01*
Y420888D01*
X194416Y424028D01*
G02X195098Y423745I282J-283D01*
G01Y423287D01*
X193298Y421487D01*
Y390655D01*
G02X192616Y390372I-400J0D01*
G37*
G36*
G01X198002Y411132D02*
Y419513D01*
X199802Y421313D01*
Y437790D01*
X201016Y439005D01*
G02X201698Y438722I282J-283D01*
G01Y413864D01*
X198684Y410849D01*
G02X198002Y411132I-282J283D01*
G37*
G36*
G01X192506Y522195D02*
G03X189009Y525714I-2306J1205D01*
G02X188426Y526069I-183J356D01*
G01Y533396D01*
G02X189109Y533679I400J0D01*
G01X194848Y527939D01*
Y521980D01*
G02X194335Y521596I-400J-1D01*
G03X192959Y521622I-735J-2496D01*
G02X192506Y522195I-99J388D01*
G37*
%LPC*%
G75*
G36*
G01X91264Y1165136D02*
G02X86736Y1169664I-2264J2264D01*
G01X94698Y1177626D01*
Y1250742D01*
X102598Y1258642D01*
Y1413647D01*
G02X102319Y1414641I2903J1351D01*
G03X101612Y1414850I-398J-45D01*
G02X97631Y1414798I-2012J1650D01*
G01X89295D01*
X82898Y1421195D01*
Y1449405D01*
X84303Y1450810D01*
X84300Y1450897D01*
G02X87003Y1453600I2600J103D01*
G01X87090Y1453597D01*
X87898Y1454405D01*
Y1462031D01*
G02Y1465969I1702J1969D01*
G01Y1468405D01*
G03X87216Y1468688I-400J0D01*
G01X85764Y1467236D01*
G02X81098Y1471617I-2264J2264D01*
G01Y1489374D01*
X60198Y1510274D01*
Y1516293D01*
G03X59626Y1516654I-400J0D01*
G02X56333Y1517560I-1126J2346D01*
G03X55667I-333J-222D01*
G02Y1520440I-2167J1440D01*
G03X56333I333J222D01*
G02X59626Y1521346I2167J-1440D01*
G03X60198Y1521707I172J361D01*
G01Y1538013D01*
G03X59759Y1538411I-400J0D01*
G02X57197Y1539790I-259J2589D01*
G03X56504Y1539817I-354J-186D01*
G02X56603Y1542410I-2204J1383D01*
G03X57296Y1542383I354J186D01*
G02X59759Y1543589I2204J-1383D01*
G03X60198Y1543987I39J398D01*
G01Y1560069D01*
G03X59492Y1560326I-400J0D01*
G02Y1563674I-1992J1674D01*
G03X60198Y1563931I306J257D01*
G01Y1604993D01*
G03X59626Y1605354I-400J0D01*
G02Y1610046I-1126J2346D01*
G03X60198Y1610407I172J361D01*
G01Y1612802D01*
X57000Y1616000D01*
X56465D01*
Y1615677D01*
X56575Y1615622D01*
G02X53728Y1615294I-1175J-2322D01*
G03X53471Y1616000I-257J306D01*
G01X53000D01*
X49500Y1619500D01*
Y1743000D01*
X59000Y1752500D01*
Y1870500D01*
X62000Y1873500D01*
X120500D01*
X132500Y1861500D01*
Y1786500D01*
X136000Y1783000D01*
X140500D01*
X143000Y1780500D01*
Y1777000D01*
X140500Y1774500D01*
X135500D01*
X132500Y1771500D01*
Y1677000D01*
X140000Y1669500D01*
X184500D01*
X186500Y1667500D01*
Y1617500D01*
X183500Y1614500D01*
X148145D01*
G03X147859Y1613820I0J-400D01*
G02X144141I-1859J-1820D01*
G03X143855Y1614500I-286J280D01*
G01X124145D01*
G03X123859Y1613820I0J-400D01*
G02X120141I-1859J-1820D01*
G03X119855Y1614500I-286J280D01*
G01X118145D01*
G03X117859Y1613820I0J-400D01*
G02X113469Y1612605I-1859J-1820D01*
G03X113080Y1613098I-389J93D01*
G01X92117D01*
X91702Y1612683D01*
Y1607305D01*
G03X92421Y1607065I400J1D01*
G02Y1603935I2079J-1565D01*
G03X91702Y1603695I-319J-241D01*
G01Y1570325D01*
G03X92354Y1570016I400J1D01*
G02Y1565984I1646J-2016D01*
G03X91702Y1565675I-252J-310D01*
G01Y1564325D01*
G03X92354Y1564016I400J1D01*
G02Y1559984I1646J-2016D01*
G03X91702Y1559675I-252J-310D01*
G01Y1558325D01*
G03X92354Y1558016I400J1D01*
G02Y1553984I1646J-2016D01*
G03X91702Y1553675I-252J-310D01*
G01Y1552325D01*
G03X92354Y1552016I400J1D01*
G02X95340Y1547769I1646J-2016D01*
G03X95263Y1547144I206J-343D01*
G01X98715Y1543691D01*
G03X99398Y1543977I283J283D01*
G02X101977Y1541398I2602J23D01*
G03X101691Y1540715I-3J-400D01*
G01X125405Y1517002D01*
X128658D01*
X135114Y1510546D01*
X135187Y1510540D01*
G02X137309Y1508185I-179J-2295D01*
G01X137307Y1508099D01*
X138310Y1507097D01*
X138397Y1507100D01*
G02X139279Y1506983I104J-2600D01*
G03X139798Y1507364I119J381D01*
G01Y1510088D01*
X132541Y1517345D01*
X132526Y1517356D01*
G02X131856Y1518026I1474J2144D01*
G01X131845Y1518041D01*
X131798Y1518088D01*
Y1518112D01*
X131770Y1518159D01*
G02X131511Y1518743I2231J1339D01*
G01X131496Y1518791D01*
X127426Y1522860D01*
G03X126791Y1522767I-283J-283D01*
G02X123267Y1526291I-2291J1233D01*
G03X123360Y1526926I-190J352D01*
G01X121926Y1528360D01*
G03X121291Y1528267I-283J-283D01*
G02X117767Y1531791I-2291J1233D01*
G03X117860Y1532426I-190J352D01*
G01X114235Y1536051D01*
G03X113626Y1535999I-283J-283D01*
G02X109999Y1539626I-2126J1501D01*
G03X110051Y1540235I-231J326D01*
G01X106298Y1543988D01*
Y1555113D01*
G02Y1557887I2202J1387D01*
G01Y1568327D01*
X106290Y1568354D01*
G02X110710I2210J646D01*
G01X110702Y1568327D01*
Y1557887D01*
G02Y1555113I-2202J-1387D01*
G01Y1545812D01*
X111232Y1545281D01*
X111446Y1545495D01*
X111430Y1545595D01*
G02X114069Y1543399I2570J405D01*
G03X113797Y1542716I11J-400D01*
G01X118716Y1537797D01*
G03X119399Y1538069I283J283D01*
G02X122069Y1535399I2601J-69D01*
G03X121797Y1534716I11J-400D01*
G01X134450Y1522064D01*
X134509Y1522052D01*
G02X136600Y1519589I-509J-2552D01*
G01X136603Y1519510D01*
X144201Y1511912D01*
Y1495473D01*
X144210Y1495446D01*
G02X139790I-2210J-646D01*
G01X139798Y1495473D01*
Y1501636D01*
G03X139279Y1502017I-400J0D01*
G02X137894Y1501970I-778J2483D01*
G03X137428Y1501437I-93J-389D01*
G02X132691Y1499300I-2428J-937D01*
G03X132025Y1499366I-355J-185D01*
G02X127975I-2025J1634D01*
G03X127309Y1499300I-311J-251D01*
G02X127199Y1499108I-2311J1197D01*
G03X127368Y1498802I169J-106D01*
G01X127712D01*
X133381Y1493133D01*
X133406Y1493119D01*
G02X130281Y1489994I-1106J-2019D01*
G01X130267Y1490019D01*
X125888Y1494398D01*
X94588D01*
X81325Y1507662D01*
X81271Y1507675D01*
G02X79375Y1509571I629J2525D01*
G01X79362Y1509625D01*
X75237Y1513750D01*
G03X74561Y1513538I-282J-283D01*
G02X71538Y1516561I-2561J462D01*
G03X71750Y1517237I-71J394D01*
G01X67284Y1521702D01*
G03X66602Y1521419I-282J-283D01*
G01Y1512926D01*
X87264Y1492264D01*
G02X87543Y1488055I-2264J-2264D01*
G01X87501Y1488001D01*
Y1487691D01*
G03X87843Y1487549I200J-1D01*
G01X88703Y1488410D01*
X88700Y1488497D01*
G02X91302Y1485998I2600J103D01*
G01Y1465969D01*
G02Y1462031I-1702J-1969D01*
G01Y1452995D01*
X89497Y1451190D01*
X89500Y1451103D01*
G02X86797Y1448400I-2600J-103D01*
G01X86710Y1448403D01*
X86302Y1447995D01*
Y1442514D01*
X86527D01*
X86551Y1442520D01*
G02X86571Y1442525I641J-2522D01*
G01X86625Y1442538D01*
X90488Y1446402D01*
X90788D01*
X93321Y1448934D01*
X93334Y1448988D01*
G02X95230Y1450884I2525J-629D01*
G01X95284Y1450897D01*
X97598Y1453212D01*
Y1454212D01*
X97570Y1454259D01*
G02X102002Y1454213I2230J1341D01*
G01Y1451388D01*
X98397Y1447784D01*
X98384Y1447730D01*
G02X96488Y1445834I-2525J629D01*
G01X96434Y1445821D01*
X92612Y1441998D01*
X92312D01*
X90663Y1440350D01*
X93502Y1437512D01*
Y1429388D01*
X90532Y1426418D01*
X90494D01*
X90439Y1426375D01*
G02X90402Y1426345I-1468J1773D01*
G01X90392Y1426337D01*
X90024Y1425970D01*
X89673D01*
X89646Y1425961D01*
G02X87042Y1426961I-645J2210D01*
G03X86302Y1426751I-340J-210D01*
G01Y1422605D01*
X90705Y1418202D01*
X97631D01*
G02X102156Y1416989I1969J-1702D01*
G03X102876Y1416835I393J75D01*
G02X107764Y1417264I2624J-1835D01*
G01X109002Y1416026D01*
Y1255990D01*
X101102Y1248090D01*
Y1174974D01*
X91264Y1165136D01*
G37*
G36*
G01X152884Y1580957D02*
G02Y1583043I-2384J1043D01*
G03X153616I366J161D01*
G02Y1580957I2384J-1043D01*
G03X152884I-366J-161D01*
G37*
G36*
G01X129501Y1565053D02*
G02X127633Y1564714I-501J-2553D01*
G03X127499Y1565447I-210J340D01*
G02X129367Y1565786I501J2553D01*
G03X129501Y1565053I210J-340D01*
G37*
G36*
G01X156440Y1122167D02*
G02X153560I-1440J-2167D01*
G03Y1122833I-222J333D01*
G02X153957Y1127384I1440J2167D01*
G03Y1128116I-161J366D01*
G02X156043I1043J2384D01*
G03Y1127384I161J-366D01*
G02X156440Y1122833I-1043J-2384D01*
G03Y1122167I222J-333D01*
G37*
G36*
G01X94352Y108863D02*
G02X92415Y109226I-1352J-1863D01*
G03X92548Y109937I-102J387D01*
G02X94485Y109574I1352J1863D01*
G03X94352Y108863I102J-387D01*
G37*
G36*
G01X93048Y90796D02*
G03Y90204I269J-296D01*
G02X89952I-1548J-1704D01*
G03Y90796I-269J296D01*
G02X90038Y94278I1548J1704D01*
G03X89964Y94944I-254J309D01*
G02X92462Y95222I1036J2056D01*
G03X92536Y94556I254J-309D01*
G02X93048Y90796I-1036J-2056D01*
G37*
G36*
G01X95800Y1129809D02*
G03X95866Y1130475I-185J355D01*
G02X98700Y1130191I1634J2025D01*
G03X98634Y1129525I185J-355D01*
G02X98950Y1129223I-1633J-2025D01*
G03X99550I300J264D01*
G02X103450I1950J-1723D01*
G03X104050I300J264D01*
G02Y1125777I1950J-1723D01*
G03X103450I-300J-264D01*
G02X99550I-1950J1723D01*
G03X98950I-300J-264D01*
G02X95800Y1129809I-1950J1723D01*
G37*
G36*
G01X102399Y1433476D02*
X102888D01*
X106939Y1437527D01*
X106925Y1437627D01*
G02X109127Y1435425I2575J373D01*
G01X109027Y1435439D01*
X104169Y1430581D01*
X104157Y1430520D01*
G02X101492Y1428400I-2557J480D01*
G03X101079Y1428054I-17J-400D01*
G02X98608Y1431000I-2579J346D01*
G03X99021Y1431346I17J400D01*
G02X102370Y1433485I2579J-346D01*
G01X102399Y1433476D01*
G37*
G36*
G01X176827Y1567298D02*
X174310D01*
X171118Y1564106D01*
G03X171147Y1563514I283J-283D01*
G02X167486Y1559853I-1647J-2014D01*
G03X166894Y1559882I-309J-254D01*
G01X159202Y1552190D01*
Y1545904D01*
G03X159841Y1545583I400J-1D01*
G02Y1541417I1559J-2083D01*
G03X159202Y1541096I-239J-320D01*
G01Y1529387D01*
G02Y1526613I-2202J-1387D01*
G01Y1499088D01*
X155533Y1495419D01*
X155519Y1495394D01*
G02X152394Y1498519I-2019J1106D01*
G01X152419Y1498533D01*
X154798Y1500912D01*
Y1526613D01*
G02Y1529387I2202J1387D01*
G01Y1554014D01*
X160725Y1559940D01*
G03X160556Y1560606I-283J283D01*
G02X163794Y1563844I744J2494D01*
G03X164460Y1563675I383J114D01*
G01X165280Y1564496D01*
G03X165251Y1565088I-283J283D01*
G02X168912Y1568749I1647J2014D01*
G03X169504Y1568720I309J254D01*
G01X172486Y1571702D01*
X176827D01*
X176854Y1571710D01*
G02Y1567290I646J-2210D01*
G01X176827Y1567298D01*
G37*
G36*
G01X149702Y1506387D02*
G02X149701Y1503613I-2202J-1386D01*
G01Y1498673D01*
X149710Y1498646D01*
G02X145290I-2210J-646D01*
G01X145298Y1498673D01*
Y1503613D01*
G02Y1506387I2202J1387D01*
G01Y1520588D01*
X141316Y1524570D01*
Y1538613D01*
G02Y1541387I2202J1387D01*
G01Y1566847D01*
X141308Y1566874D01*
G02X145728I2210J646D01*
G01X145720Y1566847D01*
Y1566340D01*
G03X146370Y1566028I400J0D01*
G02Y1561972I1630J-2028D01*
G03X145720Y1561660I-250J-312D01*
G01Y1560340D01*
G03X146370Y1560028I400J0D01*
G02Y1555972I1630J-2028D01*
G03X145720Y1555660I-250J-312D01*
G01Y1552340D01*
G03X146370Y1552028I400J0D01*
G02Y1547972I1630J-2028D01*
G03X145720Y1547660I-250J-312D01*
G01Y1544340D01*
G03X146370Y1544028I400J0D01*
G02X146668Y1539765I1630J-2028D01*
G03X146071Y1539498I-204J-344D01*
G02X145720Y1538613I-2554J501D01*
G01Y1530340D01*
G03X146370Y1530028I400J0D01*
G02X147707Y1525415I1630J-2028D01*
G03X147379Y1524734I-45J-398D01*
G01X149702Y1522412D01*
Y1506387D01*
G37*
G36*
G01X53194Y1581071D02*
G03X52568Y1581098I-324J-235D01*
G02X52706Y1584329I-1968J1702D01*
G03X53332Y1584302I324J235D01*
G02X53194Y1581071I1968J-1702D01*
G37*
G36*
G01Y1587571D02*
G03X52568Y1587598I-324J-235D01*
G02X52706Y1590829I-1968J1702D01*
G03X53332Y1590802I324J235D01*
G02X53194Y1587571I1968J-1702D01*
G37*
G36*
G01Y1593571D02*
G03X52568Y1593598I-324J-235D01*
G02X52706Y1596829I-1968J1702D01*
G03X53332Y1596802I324J235D01*
G02X53194Y1593571I1968J-1702D01*
G37*
G36*
G01Y1599571D02*
G03X52568Y1599598I-324J-235D01*
G02X52706Y1602829I-1968J1702D01*
G03X53332Y1602802I324J235D01*
G02X53194Y1599571I1968J-1702D01*
G37*
G36*
G01X133333Y473060D02*
G03X132667I-333J-222D01*
G02Y475940I-2167J1440D01*
G03X133333I333J222D01*
G02Y473060I2167J-1440D01*
G37*
G36*
G01Y466560D02*
G03X132667I-333J-222D01*
G02Y469440I-2167J1440D01*
G03X133333I333J222D01*
G02Y466560I2167J-1440D01*
G37*
G36*
G01Y459560D02*
G03X132667I-333J-222D01*
G02Y462440I-2167J1440D01*
G03X133333I333J222D01*
G02Y459560I2167J-1440D01*
G37*
G36*
G01Y452560D02*
G03X132667I-333J-222D01*
G02Y455440I-2167J1440D01*
G03X133333I333J222D01*
G02Y452560I2167J-1440D01*
G37*
G36*
G01X61974Y461633D02*
G03X61881Y462219I-311J251D01*
G02X61147Y465861I1419J2181D01*
G03X61054Y466407I-331J225D01*
G02X60787Y470367I1546J2093D01*
G03X60774Y470953I-278J287D01*
G02X60599Y474677I1726J1947D01*
G03Y475223I-292J273D01*
G02X64401I1901J1777D01*
G03Y474677I292J-273D01*
G02X64313Y471033I-1901J-1777D01*
G03X64326Y470447I278J-287D01*
G02X64753Y467039I-1726J-1947D01*
G03X64846Y466493I331J-225D01*
G02X65326Y462767I-1546J-2093D01*
G03X65419Y462181I311J-251D01*
G02X65723Y458050I-1419J-2181D01*
G03Y457450I264J-300D01*
G02Y453550I-1723J-1950D01*
G03Y452950I264J-300D01*
G02Y449050I-1723J-1950D01*
G03Y448450I264J-300D01*
G02X62277I-1723J-1950D01*
G03Y449050I-264J300D01*
G02Y452950I1723J1950D01*
G03Y453550I-264J300D01*
G02Y457450I1723J1950D01*
G03Y458050I-264J300D01*
G02X61974Y461633I1723J1950D01*
G37*
G36*
G01X72438Y420081D02*
G03X72398Y420747I-240J320D01*
G02X75262Y420919I1302J2253D01*
G03X75302Y420253I240J-320D01*
G02X72438Y420081I-1302J-2253D01*
G37*
G36*
G01X118043Y457384D02*
G02X115957I-1043J-2384D01*
G03Y458116I-161J366D01*
G02Y462884I1043J2384D01*
G03Y463616I-161J366D01*
G02Y468384I1043J2384D01*
G03Y469116I-161J366D01*
G02X118043I1043J2384D01*
G03Y468384I161J-366D01*
G02Y463616I-1043J-2384D01*
G03Y462884I161J-366D01*
G02Y458116I-1043J-2384D01*
G03Y457384I161J-366D01*
G37*
G36*
G01X83340Y409363D02*
G02Y411637I-2340J1137D01*
G03X84060I360J175D01*
G02X88784Y411543I2340J-1137D01*
G03X89516I366J161D01*
G02Y409457I2384J-1043D01*
G03X88784I-366J-161D01*
G02X84060Y409363I-2384J1043D01*
G03X83340I-360J-175D01*
G37*
G36*
G01X84398Y1064034D02*
G03X83932Y1064434I-400J6D01*
G02X82060Y1069167I-432J2566D01*
G03Y1069833I-222J333D01*
G02X81777Y1073950I1440J2167D01*
G03Y1074550I-264J300D01*
G02X85223I1723J1950D01*
G03Y1073950I264J-300D01*
G02X84940Y1069833I-1723J-1950D01*
G03Y1069167I222J-333D01*
G02X86102Y1066966I-1440J-2167D01*
G03X86568Y1066566I400J-6D01*
G02X88867Y1065813I432J-2566D01*
G03X89453Y1065826I287J278D01*
G02X93223Y1065956I1947J-1726D01*
G03X93769Y1065943I280J286D01*
G02X93677Y1062144I1731J-1943D01*
G03X93131Y1062157I-280J-286D01*
G02X89533Y1062287I-1731J1943D01*
G03X88947Y1062274I-287J-278D01*
G02X84398Y1064034I-1947J1726D01*
G37*
G36*
G01X168302Y493812D02*
X171401Y490712D01*
Y484187D01*
G02X168006Y480488I-2201J-1387D01*
G03X167449Y480276I-184J-355D01*
G02X163090Y481746I-2149J824D01*
G01X163098Y481773D01*
Y487988D01*
X160298Y490788D01*
Y527227D01*
X160290Y527254D01*
G02X164034Y529617I2210J646D01*
G03X164566I266J298D01*
G02X168310Y527254I1534J-1717D01*
G01X168302Y527227D01*
Y493812D01*
G37*
G36*
G01X148677Y426240D02*
G02X147423Y424360I1323J-2241D01*
G03X146823Y424760I-396J56D01*
G02X148077Y426640I-1323J2241D01*
G03X148677Y426240I396J-56D01*
G37*
G54D27*
X182500Y1584500D03*
X138500Y1606000D03*
X150500Y1600000D03*
X156000Y1606000D03*
X156500Y1600000D03*
X164000Y1606000D03*
X182500Y1592000D03*
X148000Y1606000D03*
X182500Y1599400D03*
X172000Y1606000D03*
X150500Y1591000D03*
X156500D03*
X150000Y1576000D03*
X156000D03*
X170000Y1541000D03*
X136000Y1568000D03*
Y1542000D03*
Y1536000D03*
Y1562000D03*
Y1555000D03*
Y1548000D03*
X168500Y1533500D03*
X170000Y1555000D03*
X156000Y1570000D03*
X154000Y1564000D03*
X170000Y1548500D03*
X168500Y1526000D03*
X150000Y1570000D03*
X136000Y1528000D03*
X174000Y1522000D03*
X174500Y1503500D03*
Y1509500D03*
X174000Y1515500D03*
X148300Y1465000D03*
X116948Y1892000D03*
X124500Y1892403D03*
X132000Y1892000D03*
X113500Y1605500D03*
X128000Y1606000D03*
X122000Y1600000D03*
X104000Y1605500D03*
X116000Y1600000D03*
X122000Y1592000D03*
X116000D03*
Y1584000D03*
X122000D03*
Y1576000D03*
X116000D03*
X129000Y1555500D03*
X122000Y1558000D03*
X114000Y1552000D03*
X122000D03*
X114000Y1558000D03*
X122000Y1564000D03*
X121800Y1569929D03*
X114000Y1564000D03*
X102000Y1562000D03*
Y1550000D03*
Y1556000D03*
Y1568000D03*
X115900Y1569700D03*
X129000Y1535000D03*
Y1549000D03*
X122000Y1546000D03*
X129000Y1542500D03*
X42000Y1784400D03*
X48400Y1746900D03*
X41600D03*
X54500Y1574000D03*
X57000Y1568500D03*
X31600Y1024300D03*
X40000Y659000D03*
X68000Y286000D03*
Y296000D03*
Y320000D03*
Y312000D03*
X76000Y296000D03*
X68000Y304000D03*
X74000Y390000D03*
X66000D03*
X58000D03*
X74000Y408000D03*
X66000D03*
Y418000D03*
Y426000D03*
X58000D03*
X74000Y400000D03*
X66000D03*
X58000D03*
Y408000D03*
Y417500D03*
X58100Y431900D03*
X102000Y312000D03*
X104000Y304000D03*
X94000D03*
Y312000D03*
Y320000D03*
X114000Y296000D03*
X106000D03*
X96000D03*
X86000D03*
X118000Y396000D03*
Y386000D03*
X89800Y446000D03*
X118000Y424000D03*
Y404000D03*
Y414000D03*
X129000Y485500D03*
X120000D03*
X110800Y482600D03*
Y488600D03*
Y494600D03*
X129000Y493500D03*
X120000D03*
X122500Y450500D03*
Y457500D03*
Y463500D03*
X121500Y475500D03*
X122500Y469500D03*
X117000Y449000D03*
X89800Y452900D03*
Y459000D03*
X111500Y473000D03*
X89800Y464800D03*
X120000Y501500D03*
X129000Y517500D03*
X110800Y500600D03*
X84500Y514400D03*
X129000Y501500D03*
Y509500D03*
X110800Y512600D03*
X120000Y517500D03*
X110800Y506600D03*
X120000Y509500D03*
Y523500D03*
X129000D03*
X134000Y396000D03*
Y386000D03*
Y404500D03*
Y414000D03*
Y424000D03*
X137000Y493000D03*
X136500Y485500D03*
X137000Y510000D03*
X137500Y523500D03*
X137000Y501500D03*
X137500Y517500D03*
X97250Y1023500D03*
X142000Y291000D03*
X143400Y318700D03*
X174000Y316000D03*
X164000D03*
X182000Y296000D03*
X172000D03*
X162000D03*
X172000Y310000D03*
X182000D03*
X184000Y303000D03*
X176000Y302000D03*
X166000D03*
X143300Y343400D03*
X151300Y298200D03*
X150000Y386000D03*
Y396000D03*
X161600Y445900D03*
X150000Y404000D03*
Y414000D03*
X161900Y451600D03*
X162000Y457600D03*
X161900Y463300D03*
X173700Y513900D03*
X173500Y506000D03*
X173600Y498800D03*
X157100Y500000D03*
X156800Y515400D03*
Y506900D03*
G54D28*
X165000Y1370500D03*
Y1380500D03*
Y1390500D03*
X15906Y1920394D03*
Y1910394D03*
Y1900394D03*
Y1890394D03*
Y1880394D03*
Y1227323D03*
Y1217323D03*
Y1207323D03*
Y1197323D03*
Y1187323D03*
Y781181D03*
Y771181D03*
Y761181D03*
Y751181D03*
Y741181D03*
Y88110D03*
Y78110D03*
Y68110D03*
Y58110D03*
Y48110D03*
G54D29*
X169606Y204409D03*
X179606Y224409D03*
Y214409D03*
Y204409D03*
X149606Y191889D03*
Y181889D03*
X159606Y191889D03*
Y181889D03*
X169606Y191889D03*
Y181889D03*
X179606Y191889D03*
Y181889D03*
X149606Y171889D03*
Y161889D03*
X159606Y171889D03*
Y161889D03*
X169606Y171889D03*
Y161889D03*
X179606Y171889D03*
Y161889D03*
X90709D03*
X100709D03*
X110709D03*
X80709Y256929D03*
Y266929D03*
Y276929D03*
Y286929D03*
X110709Y256929D03*
Y266929D03*
X100709Y256929D03*
Y266929D03*
X90709Y256929D03*
Y266929D03*
X110709Y276929D03*
Y286929D03*
X100709Y276929D03*
Y286929D03*
X90709Y276929D03*
Y286929D03*
X159606Y266929D03*
X149606Y256929D03*
Y266929D03*
X179606Y276929D03*
Y286929D03*
X169606Y276929D03*
Y286929D03*
X159606Y276929D03*
Y286929D03*
X149606Y276929D03*
Y286929D03*
G54D30*
X112000Y101000D03*
X104500D03*
X93500Y101500D03*
X109500Y62000D03*
X89500Y49500D03*
X99500Y61000D03*
X115000Y76500D03*
X109000D03*
X98500Y73000D03*
X115500Y59500D03*
X97000Y51500D03*
X64500Y53000D03*
X70454Y60031D03*
X46500Y511000D03*
X46000Y516000D03*
X91250Y704700D03*
X82094Y1112500D03*
G54D31*
X31299Y1737638D03*
Y1747638D03*
Y1629941D03*
Y1609941D03*
Y1619941D03*
Y1064587D03*
Y1044587D03*
Y1054587D03*
Y913917D03*
Y923917D03*
Y903917D03*
G54D24*
X152500Y1906000D03*
X150000Y64500D03*
G54D33*
X149606Y119409D03*
X80709D03*
Y329409D03*
X149606D03*
G54D32*
Y139409D03*
X80709D03*
Y309409D03*
X149606D03*
G54D35*
X29921Y1943701D03*
Y1857086D03*
Y1250630D03*
X30000Y1164000D03*
X29921Y804488D03*
Y717874D03*
Y111417D03*
Y24803D03*
G54D34*
X47244Y1900393D03*
Y1467165D03*
Y1207323D03*
Y68110D03*
G54D25*
X179134Y1889764D03*
Y1161417D03*
X179133Y570866D03*
X179134Y78740D03*
X27559Y1811023D03*
Y157480D03*
G54D26*
X161417Y1823031D03*
Y1747835D03*
X178937Y1328740D03*
%LPD*%
G75*
G36*
G01X96412Y1498802D02*
X84438Y1510775D01*
X84425Y1510829D01*
G03X82529Y1512725I-2525J-629D01*
G01X82475Y1512738D01*
X69902Y1525312D01*
Y1568027D01*
X69910Y1568054D01*
G03X67105Y1570924I-2210J646D01*
G02X66602Y1571310I-103J386D01*
G01Y1601425D01*
G02X67228Y1601755I400J0D01*
G03X71208Y1604592I1472J2145D01*
G02X71595Y1605098I386J106D01*
G03X71945Y1605121I5J2602D01*
G02X72398Y1604724I53J-397D01*
G01Y1542695D01*
X80210Y1534884D01*
G02X79937Y1534201I-283J-283D01*
G03X82601Y1531537I63J-2601D01*
G02X83284Y1531810I400J-10D01*
G01X88418Y1526676D01*
G02X88104Y1525994I-283J-283D01*
G03X90494Y1523604I-204J-2594D01*
G02X91176Y1523918I399J31D01*
G01X93114Y1521980D01*
G02X92853Y1521298I-283J-283D01*
G03X91908Y1516338I147J-2598D01*
G02X92041Y1515712I-168J-363D01*
G03X95092Y1516362I1959J-1712D01*
G02X94959Y1516988I168J363D01*
G03X95598Y1518553I-1959J1713D01*
G02X96280Y1518814I399J-22D01*
G01X107051Y1508043D01*
G02X106909Y1507702I-142J-141D01*
G01X106471D01*
X106411Y1507766D01*
G03Y1504234I-1911J-1766D01*
G01X106471Y1504298D01*
X106695D01*
G02X106935Y1503579I-1J-400D01*
G03X106826Y1499508I1565J-2079D01*
G02X106569Y1498802I-257J-306D01*
G01X96412D01*
G37*
G36*
G01X183500Y1665500D02*
Y1634000D01*
X179500Y1630000D01*
X55500D01*
X54500Y1631000D01*
Y1638000D01*
X52000Y1640500D01*
Y1742500D01*
X61000Y1751500D01*
Y1868500D01*
X64000Y1871500D01*
X119500D01*
X128000Y1863000D01*
Y1785500D01*
X125500Y1783000D01*
X117000D01*
X114500Y1780500D01*
Y1777000D01*
X117000Y1774500D01*
X126000D01*
X128000Y1772500D01*
Y1676500D01*
X137000Y1667500D01*
X181500D01*
X183500Y1665500D01*
G37*
G36*
G01X86302Y1429591D02*
Y1437040D01*
G02X86768Y1437434I400J0D01*
G03X87296Y1437400I430J2566D01*
G01X87384Y1437403D01*
X89098Y1435688D01*
Y1431212D01*
X88708Y1430822D01*
X88649D01*
X88130Y1430303D01*
X88095Y1430288D01*
G03X87042Y1429381I906J-2116D01*
G02X86302Y1429591I-340J210D01*
G37*
%LPC*%
G75*
G54D27*
X73900Y1535900D03*
X85200Y1515000D03*
G54D26*
X96457Y1747835D03*
Y1823031D03*
%LPD*%
G75*
G54D10*
G01X63500Y63500D02*
Y65000D01*
X47824Y80676D01*
Y165176D01*
X45800Y167200D01*
Y183000D01*
X41400Y187400D01*
Y204700D01*
X45420Y208720D01*
Y235600D01*
X34600Y246420D01*
Y256300D01*
X30100Y260800D01*
Y333094D01*
X26100Y337094D01*
Y364895D01*
X21121Y369874D01*
Y449060D01*
X19254Y450927D01*
Y464554D01*
X30800Y476100D01*
Y526900D01*
X43000Y539100D01*
Y577500D01*
X64000Y598500D01*
Y612900D01*
X69600Y618500D01*
Y662700D01*
G01X15906Y491339D02*
X21456Y496889D01*
Y526544D01*
X17621Y530379D01*
Y560121D01*
X27369Y569869D01*
Y573431D01*
X27000Y573800D01*
G01X38000Y589500D02*
Y588500D01*
X27000Y577500D01*
Y573800D01*
G01X56927Y1130027D02*
X72300Y1145400D01*
Y1154900D01*
X75263Y1157863D01*
Y1329937D01*
X17621Y1387579D01*
Y1432121D01*
X21456Y1435956D01*
Y1486990D01*
X14121Y1494325D01*
Y1640215D01*
X16601Y1642695D01*
Y1769728D01*
X39179Y1792306D01*
G01X15906Y1457165D02*
X11921Y1453180D01*
Y1382684D01*
X68800Y1325805D01*
Y1178800D01*
G01X51200Y827000D02*
Y780700D01*
X39794Y769294D01*
Y754206D01*
X42400Y751600D01*
Y703100D01*
X46600Y698900D01*
Y597600D01*
X38500Y589500D01*
X38000D01*
G01X61207Y828350D02*
X62750Y826807D01*
Y682005D01*
X67525Y677230D01*
Y664775D01*
X69600Y662700D01*
G01X56927Y1130027D02*
X48800Y1121900D01*
Y913200D01*
X64600Y897400D01*
Y882700D01*
G01X60900Y893000D02*
X61600Y892300D01*
Y885200D01*
G01X60900Y893000D02*
Y897500D01*
X46600Y911800D01*
Y1123100D01*
X68400Y1144900D01*
Y1168200D01*
X67250Y1169350D01*
Y1177250D01*
X68800Y1178800D01*
G01X58500Y912500D02*
Y907000D01*
X67200Y898300D01*
Y888800D01*
G01X51000Y1018000D02*
X51025Y1017975D01*
Y923975D01*
X58500Y916500D01*
Y912500D01*
G01X99600Y1416500D02*
X90000D01*
X84600Y1421900D01*
Y1448700D01*
X86900Y1451000D01*
G01X83000Y1619703D02*
X80700Y1617403D01*
Y1546300D01*
X120500Y1506500D01*
X121000D01*
G01X141300Y1625000D02*
X82073D01*
X76300Y1619227D01*
Y1612972D01*
X76299Y1612971D01*
Y1602029D01*
X76300Y1602028D01*
Y1544312D01*
X113000Y1507612D01*
Y1506500D01*
G01X113200Y1622800D02*
X83000D01*
X82104Y1621904D01*
X82089D01*
X78500Y1618315D01*
Y1612060D01*
X78499Y1612059D01*
Y1602941D01*
X78500Y1602940D01*
Y1545224D01*
X117000Y1506724D01*
Y1506500D01*
G01X169876Y1626303D02*
X168679Y1627500D01*
X81461D01*
X74100Y1620139D01*
Y1613884D01*
X74099Y1613883D01*
Y1601117D01*
X74100Y1601116D01*
Y1543400D01*
X109000Y1508500D01*
Y1506500D01*
G01X113200Y1619300D02*
X113000Y1619500D01*
X89500D01*
X85251Y1615251D01*
Y1548025D01*
X122376Y1510900D01*
X124598D01*
X128999Y1506499D01*
G01X83050Y1616000D02*
Y1547114D01*
X121464Y1508700D01*
X122800D01*
X125000Y1506500D01*
G01X86500Y723500D02*
Y795000D01*
X105763Y814263D01*
G01X114900Y824100D02*
Y823400D01*
X105763Y814263D01*
G01X131174Y1412700D02*
X131179Y1412695D01*
Y1096321D01*
X139376Y1088124D01*
Y1078814D01*
X139375Y1078813D01*
Y1076929D01*
X139378Y1076926D01*
Y1024147D01*
X141225Y1022300D01*
Y1013275D01*
X161700Y992800D01*
X165382D01*
X169525Y988657D01*
Y849156D01*
X150625Y830256D01*
Y734975D01*
X155292Y730308D01*
Y694592D01*
X155125Y694425D01*
Y679575D01*
X155200Y679500D01*
G01X133799Y1440699D02*
X134600Y1439898D01*
Y1423649D01*
X131174Y1420223D01*
Y1412700D01*
G01X86900Y1451000D02*
X89600Y1453700D01*
Y1464000D01*
G01D02*
Y1486900D01*
X91300Y1488600D01*
G01X110000Y1429500D02*
X111500Y1431000D01*
X121500D01*
X127000Y1436500D01*
X132000D01*
G01X117000Y1435200D02*
X120191D01*
X122500Y1437509D01*
G01D02*
X125690Y1440699D01*
X133799D01*
G01X121000Y1506500D02*
Y1503500D01*
X119500Y1502000D01*
Y1501000D01*
G01X108500Y1501500D02*
X113000Y1506000D01*
Y1506500D01*
G01X117000D02*
Y1504300D01*
X114500Y1501800D01*
G01X109000Y1506500D02*
X108500Y1506000D01*
X104500D01*
G01X141500Y1621600D02*
X118800D01*
X114200Y1617000D01*
X90500D01*
X87451Y1613951D01*
Y1548937D01*
X123288Y1513100D01*
X125900D01*
X133000Y1506000D01*
Y1505500D01*
G01X135000Y1500500D02*
Y1502500D01*
X133000Y1504500D01*
Y1505500D01*
G01X130000Y1501000D02*
Y1502000D01*
X128999Y1503001D01*
Y1506499D01*
G01X125000Y1506500D02*
Y1500500D01*
G01X135008Y1508245D02*
X127953Y1515300D01*
X124700D01*
X90000Y1550000D01*
Y1613388D01*
X91412Y1614800D01*
X115277D01*
X119677Y1619200D01*
X142500D01*
X147300Y1624000D01*
X170753D01*
X173270Y1626517D01*
G01X138500Y1504500D02*
X135008Y1507992D01*
Y1508245D01*
G01X157500Y1454800D02*
Y1449000D01*
X156000Y1447500D01*
G01X151500Y1438500D02*
X156000Y1443000D01*
Y1447500D01*
X-222440Y19685D03*
Y1948818D03*
X29921Y24803D03*
Y111417D03*
Y458031D03*
Y544646D03*
Y717874D03*
Y804488D03*
X30000Y1164000D03*
X29921Y1250630D03*
Y1423858D03*
Y1510472D03*
Y1857086D03*
Y1943701D03*
X47244Y68110D03*
X80709Y119409D03*
Y139409D03*
Y329409D03*
Y309409D03*
X47244Y501338D03*
Y761181D03*
Y1207323D03*
Y1467165D03*
Y1900393D03*
X149606Y119409D03*
Y139409D03*
Y329409D03*
Y309409D03*
X643700Y19685D03*
Y1948818D03*
G54D20*
G01X56800Y691000D02*
X57684Y691884D01*
Y697639D01*
G01X56800Y691000D02*
X56710Y690910D01*
Y681069D01*
G01X56800Y831000D02*
Y698523D01*
X57684Y697639D01*
G01X57500Y844500D02*
X52000Y850000D01*
Y867500D01*
G01X56800Y831000D02*
Y843800D01*
X57500Y844500D01*
G01X52000Y867500D02*
Y881300D01*
X49600Y883700D01*
Y889400D01*
G01D02*
Y903448D01*
X41675Y911373D01*
Y931224D01*
X41000Y931899D01*
G01X39300Y1105800D02*
X41675Y1103425D01*
Y932574D01*
X41000Y931899D01*
G01X39300Y1105800D02*
X41400Y1107900D01*
Y1123900D01*
X61500Y1144000D01*
Y1162700D01*
X64500Y1165700D01*
G01X85000Y1490000D02*
X84300Y1489300D01*
Y1470300D01*
X83500Y1469500D01*
G01X85000Y1490000D02*
X76500Y1498500D01*
G01D02*
X63400Y1511600D01*
Y1624700D01*
X57500Y1630600D01*
G01D02*
Y1634500D01*
G01X105500Y1415000D02*
X105800Y1414700D01*
Y1257316D01*
X97900Y1249416D01*
Y1176300D01*
X89000Y1167400D01*
G54D11*
X-181139Y20007D03*
X-180444Y1947256D03*
X150000Y64500D03*
X152500Y1906000D03*
X601704Y21248D03*
X602399Y1948497D03*
G54D21*
G01X15906Y83908D02*
Y88110D01*
G01D02*
Y92312D01*
G01X11704Y88110D02*
X15906D01*
G01D02*
X20108D01*
G01X27559Y140328D02*
Y157480D01*
G01D02*
Y174632D01*
G01X10407Y157480D02*
X27559D01*
G01D02*
X44711D01*
G01X27559Y612769D02*
Y629921D01*
G01D02*
Y647073D01*
G01X15906Y776979D02*
Y781181D01*
G01D02*
Y785383D01*
G01X11704Y781181D02*
X15906D01*
G01D02*
X20108D01*
G01X15906Y1223121D02*
Y1227323D01*
G01D02*
Y1231525D01*
G01X11704Y1227323D02*
X15906D01*
G01D02*
X20108D01*
G01X17716Y1321431D02*
Y1338583D01*
G01D02*
Y1355735D01*
G01Y1338583D02*
X34868D01*
G01X15906Y1482963D02*
Y1487165D01*
G01X12735Y1483994D02*
X15906Y1487165D01*
G01X27559Y1793871D02*
Y1811023D01*
G01D02*
Y1828175D01*
G01X10407Y1811023D02*
X27559D01*
G01D02*
X44711D01*
G01X15906Y1916192D02*
Y1920394D01*
G01D02*
Y1924596D01*
G01X11704Y1920394D02*
X15906D01*
G01D02*
X20108D01*
G01X86457Y161889D02*
X90709D01*
G01X76457Y171889D02*
X80709D01*
G01X77502Y168682D02*
X80709Y171889D01*
G01Y157637D02*
Y161889D01*
G01D02*
X84961D01*
G01X76305Y1747835D02*
X96457D01*
G01X76305Y1823031D02*
X96457D01*
G01X90709Y167637D02*
Y171889D01*
G01D02*
X94961D01*
G01X90709Y157637D02*
Y161889D01*
G01D02*
Y166141D01*
G01Y161889D02*
X94961D01*
G01X100709Y167637D02*
Y171889D01*
G01X96457D02*
X100709D01*
G01D02*
X104961D01*
G01X100709Y157637D02*
Y161889D01*
G01D02*
Y166141D01*
G01X96457Y161889D02*
X100709D01*
G01D02*
X104961D01*
G01X110709Y167637D02*
Y171889D01*
G01X106457D02*
X110709D01*
G01D02*
X114961D01*
G01X110709Y157637D02*
Y161889D01*
G01D02*
Y166141D01*
G01X106457Y161889D02*
X110709D01*
G01D02*
X114961D01*
G01X90709Y244409D02*
Y248661D01*
G01Y244409D02*
X94961D01*
G01X96457Y1727683D02*
Y1747835D01*
G01D02*
Y1767987D01*
G01Y1747835D02*
X116609D01*
G01X96457Y1802879D02*
Y1823031D01*
G01D02*
Y1843183D01*
G01Y1823031D02*
X116609D01*
G01X179134Y61588D02*
Y78740D01*
G01D02*
Y95892D01*
G01X161982Y78740D02*
X179134D01*
G01D02*
X196286D01*
G01X149606Y187637D02*
Y191889D01*
G01D02*
Y196141D01*
G01X145354Y191889D02*
X149606D01*
G01D02*
X153858D01*
G01X149606Y177637D02*
Y181889D01*
G01D02*
Y186141D01*
G01X145354Y181889D02*
X149606D01*
G01D02*
X153858D01*
G01X159606Y187637D02*
Y191889D01*
G01D02*
Y196141D01*
G01X155354Y191889D02*
X159606D01*
G01D02*
X163858D01*
G01X159606Y177637D02*
Y181889D01*
G01D02*
Y186141D01*
G01X155354Y181889D02*
X159606D01*
G01D02*
X163858D01*
G01X169606Y187637D02*
Y191889D01*
G01D02*
Y196141D01*
G01X165354Y191889D02*
X169606D01*
G01D02*
X173858D01*
G01X169606Y177637D02*
Y181889D01*
G01D02*
Y186141D01*
G01X165354Y181889D02*
X169606D01*
G01D02*
X173858D01*
G01X179606Y187637D02*
Y191889D01*
G01D02*
Y196141D01*
G01X175354Y191889D02*
X179606D01*
G01D02*
X183858D01*
G01X179606Y177637D02*
Y181889D01*
G01D02*
Y186141D01*
G01X175354Y181889D02*
X179606D01*
G01D02*
X183858D01*
G01X149606Y167637D02*
Y171889D01*
G01D02*
Y176141D01*
G01X145354Y171889D02*
X149606D01*
G01D02*
X153858D01*
G01X149606Y157637D02*
Y161889D01*
G01D02*
Y166141D01*
G01X145354Y161889D02*
X149606D01*
G01D02*
X153858D01*
G01X159606Y167637D02*
Y171889D01*
G01D02*
Y176141D01*
G01X155354Y171889D02*
X159606D01*
G01D02*
X163858D01*
G01X159606Y157637D02*
Y161889D01*
G01D02*
Y166141D01*
G01X155354Y161889D02*
X159606D01*
G01D02*
X163858D01*
G01X169606Y167637D02*
Y171889D01*
G01D02*
Y176141D01*
G01X165354Y171889D02*
X169606D01*
G01D02*
X173858D01*
G01X169606Y157637D02*
Y161889D01*
G01D02*
Y166141D01*
G01X165354Y161889D02*
X169606D01*
G01D02*
X173858D01*
G01X179606Y167637D02*
Y171889D01*
G01D02*
Y176141D01*
G01X175354Y171889D02*
X179606D01*
G01D02*
X183858D01*
G01X179606Y157637D02*
Y161889D01*
G01D02*
Y166141D01*
G01X175354Y161889D02*
X179606D01*
G01D02*
X183858D01*
G01X159606Y244409D02*
Y248661D01*
G01X155354Y244409D02*
X159606D01*
G01Y200157D02*
Y204409D01*
G01X155354D02*
X159606D01*
G01D02*
X163858D01*
G01X179133Y553714D02*
Y570866D01*
G01D02*
Y588018D01*
G01X161981Y570866D02*
X179133D01*
G01D02*
X196285D01*
G01X179134Y1144265D02*
Y1161417D01*
G01D02*
Y1178569D01*
G01X161982Y1161417D02*
X179134D01*
G01D02*
X196286D01*
G01X178937Y1308588D02*
Y1328740D01*
G01D02*
Y1348892D01*
G01X158785Y1328740D02*
X178937D01*
G01D02*
X199089D01*
G01X161417Y1727683D02*
Y1747835D01*
G01D02*
Y1767987D01*
G01X141265Y1747835D02*
X161417D01*
G01D02*
X181569D01*
G01X161417Y1802879D02*
Y1823031D01*
G01D02*
Y1843183D01*
G01X141265Y1823031D02*
X161417D01*
G01D02*
X181569D01*
G01X179134Y1872612D02*
Y1889764D01*
G01D02*
Y1906916D01*
G01X161982Y1889764D02*
X179134D01*
G01D02*
X196286D01*
G54D12*
X8594Y6500D03*
X31500Y5500D03*
X20000Y6000D03*
X17000Y36500D03*
X32000Y40000D03*
X5594Y87000D03*
Y53500D03*
X29500Y53000D03*
X26000Y87000D03*
X30800Y130300D03*
X4594Y120500D03*
X34400Y95300D03*
X14000Y141000D03*
X23500Y124000D03*
X15000Y131500D03*
X14500Y100500D03*
Y112500D03*
X4500Y105500D03*
X5000Y137500D03*
X22500Y190000D03*
X29700Y191400D03*
X5594Y153500D03*
X4594Y187500D03*
X16500Y175000D03*
X27000Y182000D03*
X14000Y184000D03*
X4500Y170500D03*
X21500Y241500D03*
X4594Y234000D03*
X24000Y212000D03*
X29000Y200500D03*
X13000Y244000D03*
X13500Y230500D03*
X13000Y212500D03*
X5000Y221000D03*
X12500Y197500D03*
X4500Y202500D03*
X28050Y256950D03*
X5094Y278000D03*
X6094Y257000D03*
X13500Y279000D03*
Y295000D03*
X5500Y295500D03*
X12500Y266500D03*
X5500Y269500D03*
X5000Y247500D03*
X19721Y267203D03*
X5594Y312000D03*
X5304Y342500D03*
X4900Y328000D03*
X13500Y303500D03*
X13000Y321000D03*
X4594Y396500D03*
X6500Y375000D03*
X27000Y371000D03*
X4800Y356200D03*
X23700Y363900D03*
X29500Y364500D03*
X27000Y377500D03*
Y384000D03*
Y389500D03*
X4594Y421000D03*
X5304Y444500D03*
Y440500D03*
X5000Y408500D03*
X5304Y434500D03*
X26500Y440000D03*
X26000Y432500D03*
X23800Y410700D03*
X5094Y469500D03*
X5000Y495000D03*
X4700Y458200D03*
X5000Y486500D03*
X5094Y600000D03*
X34100Y566600D03*
X13510Y597990D03*
X18035Y572076D03*
X14000Y614000D03*
X4594Y625000D03*
X18000Y608000D03*
X6000Y612000D03*
Y646000D03*
X26000Y656500D03*
X5594Y688500D03*
X5304Y661000D03*
X14000Y659000D03*
X23000Y677500D03*
X32000Y666000D03*
X28000Y706000D03*
X8000Y678000D03*
X31000Y700500D03*
X20000Y696000D03*
X6000Y698000D03*
Y706500D03*
X31000Y747000D03*
X22000Y746000D03*
X24000Y756000D03*
X27000Y750000D03*
X26000Y732000D03*
X18000Y724000D03*
Y732500D03*
Y712000D03*
X6000Y722000D03*
Y730500D03*
X5594Y778000D03*
X6500Y799000D03*
X9500Y804000D03*
X30000Y782000D03*
X16100Y794600D03*
X5594Y844500D03*
X6094Y819500D03*
X30500D03*
X10000Y811500D03*
X24000Y846000D03*
X24500Y853500D03*
X16000Y828000D03*
Y814000D03*
Y856000D03*
Y842000D03*
X32000Y858000D03*
Y844000D03*
X4500Y833500D03*
Y857500D03*
X26053Y828247D03*
X5094Y897500D03*
X5594Y869000D03*
X16000Y906000D03*
X32000Y886000D03*
Y872000D03*
X18000Y884000D03*
Y870000D03*
X5000Y883500D03*
X18500Y896500D03*
X23053Y861247D03*
X5304Y926000D03*
X4594Y954000D03*
X18000Y934000D03*
Y920000D03*
X16000Y962000D03*
Y948000D03*
X4500Y913000D03*
Y941500D03*
X34000Y944000D03*
Y934500D03*
X33500Y962500D03*
Y953000D03*
X26053Y938247D03*
X4594Y1013500D03*
X5594Y984500D03*
X28000Y992000D03*
X26000Y1010000D03*
X16000Y990000D03*
Y976000D03*
Y1014000D03*
Y1000000D03*
X4500Y970000D03*
Y997000D03*
X34000Y984000D03*
Y974500D03*
Y1008000D03*
X25053Y971247D03*
X31600Y1024300D03*
X4594Y1041500D03*
X6000Y1058000D03*
X33600Y1029900D03*
X16000Y1046000D03*
Y1032000D03*
X14000Y1060000D03*
X4500Y1029500D03*
X34000Y1017500D03*
X27553Y1029247D03*
X5094Y1074500D03*
X32000Y1114000D03*
X34000Y1102000D03*
Y1072000D03*
X28000D03*
X14000Y1074000D03*
Y1100000D03*
Y1086000D03*
X16000Y1110000D03*
X6000Y1096000D03*
X26100Y1088600D03*
X27218Y1097000D03*
X33550Y1080100D03*
X34000Y1144000D03*
X16000Y1124000D03*
Y1148000D03*
Y1134000D03*
Y1162000D03*
X6000Y1138000D03*
Y1118000D03*
Y1152000D03*
X26600Y1132400D03*
X24553Y1153247D03*
X5304Y1208000D03*
X4594Y1169500D03*
X24000Y1180000D03*
X16000Y1176000D03*
X5094Y1268500D03*
X8500Y1237000D03*
X30000Y1240000D03*
X16000Y1262000D03*
Y1244000D03*
X28000Y1266000D03*
X6000Y1252000D03*
X22000Y1232000D03*
X31500Y1222000D03*
X31000Y1280500D03*
X6500Y1302000D03*
X17700Y1283000D03*
X34000Y1312000D03*
X6000Y1318000D03*
X12000Y1274000D03*
Y1294000D03*
X28000Y1286000D03*
Y1300000D03*
Y1320000D03*
X19800Y1315400D03*
X13500Y1365000D03*
X8000Y1368000D03*
X30438Y1367562D03*
X30800Y1403900D03*
X31500Y1397500D03*
X5304Y1409400D03*
X4594Y1382000D03*
X7500Y1376500D03*
X32000Y1391500D03*
X4800Y1460700D03*
X4594Y1435500D03*
X34000Y1465900D03*
X5304Y1504100D03*
Y1522100D03*
X4600Y1484800D03*
X34000Y1477600D03*
X29500Y1495800D03*
X5304Y1576200D03*
Y1540500D03*
X26600Y1570100D03*
X26900Y1547900D03*
Y1559100D03*
X4594Y1607500D03*
X33100Y1587400D03*
X26700Y1579800D03*
X7500Y1640200D03*
X5304Y1659000D03*
X4700Y1676100D03*
X4594Y1632000D03*
X29000Y1671000D03*
X19250Y1663100D03*
X13900Y1706200D03*
X5304Y1723500D03*
X4900Y1708000D03*
X13100Y1728900D03*
X4594Y1691000D03*
X30000Y1731000D03*
X4594Y1775000D03*
Y1751000D03*
X12600Y1753800D03*
X13100Y1742600D03*
X12900Y1765200D03*
X14500Y1832500D03*
X12600Y1792800D03*
X12500Y1782500D03*
X4594Y1878500D03*
X14500Y1863500D03*
X5000Y1864100D03*
X18600Y1871400D03*
X4594Y1850000D03*
X15000Y1854900D03*
X27500Y1883500D03*
X14500Y1842000D03*
X28000Y1876500D03*
X29000Y1841000D03*
X13100Y1933900D03*
X24800Y1926500D03*
X5094Y1921000D03*
X4594Y1902000D03*
X35000Y1933500D03*
X35300Y1925300D03*
X34500Y1963200D03*
X16100Y1950700D03*
X5094Y1944500D03*
X15500Y1942500D03*
X4500Y1936000D03*
X6500Y1962000D03*
X25000Y1962500D03*
X12500Y1959000D03*
X63594Y7000D03*
Y25500D03*
X40594Y6000D03*
X49000Y18500D03*
X43000Y27000D03*
X64500Y40000D03*
X64000Y17000D03*
X53000Y5000D03*
X51500Y53000D03*
X74000Y45000D03*
X85000D03*
X78400Y86100D03*
X63098Y119103D03*
X52000Y115600D03*
X62598Y141103D03*
X51700Y131700D03*
X71000Y131859D03*
X37000Y124000D03*
X58749Y101151D03*
X51900Y145700D03*
X86000Y152000D03*
X69000Y153000D03*
X73500Y146000D03*
X60800Y147700D03*
X86000Y296000D03*
X68000D03*
X76000D03*
X68000Y286000D03*
Y320000D03*
Y312000D03*
Y304000D03*
X74000Y390000D03*
X66000D03*
X58000D03*
X74000Y400000D03*
X66000D03*
X58000D03*
X59104Y441094D03*
X64000Y446500D03*
Y451000D03*
X74000Y408000D03*
X66000D03*
Y418000D03*
X74000D03*
X73700Y423000D03*
X66000Y426000D03*
X58000D03*
Y408000D03*
Y417500D03*
X84500Y433000D03*
X58100Y431900D03*
X63096Y434540D03*
X68500Y434300D03*
X81000Y410500D03*
X86400D03*
X78200Y501000D03*
X82000Y483600D03*
X46000Y490500D03*
X71900Y501000D03*
X50100Y493000D03*
X42500D03*
X78200Y481700D03*
X63300Y464400D03*
X64000Y455500D03*
Y460000D03*
X62500Y472900D03*
X62600Y468500D03*
X62500Y477000D03*
X76166Y551466D03*
X78500Y506700D03*
X71800Y506900D03*
X85000Y506400D03*
X84500Y514400D03*
X72100Y521800D03*
X79400D03*
X72000Y514800D03*
X78000D03*
X51700Y522500D03*
X74942Y530983D03*
X72500Y595900D03*
X56800Y576950D03*
X36000Y554000D03*
X79122Y565700D03*
X79458Y578758D03*
X69800Y574200D03*
X38000Y589500D03*
X82900Y620600D03*
X42000Y655500D03*
X80900Y668400D03*
X79000Y675500D03*
X86443Y662853D03*
X83900Y659749D03*
X84504Y666353D03*
X84000Y674000D03*
X56710Y681069D03*
X56800Y691000D03*
X39096Y674917D03*
X43281Y674991D03*
X40000Y659000D03*
X71800Y701300D03*
X69100Y698006D03*
X74100Y669398D03*
X69600Y662700D03*
X60500Y674700D03*
X80479Y683921D03*
X50000Y712500D03*
Y749000D03*
X40000Y746500D03*
X36000Y730000D03*
X46000Y726000D03*
X82000Y806500D03*
X44000Y782000D03*
X42000Y802000D03*
Y788000D03*
X47600Y796800D03*
X56800Y831000D03*
X79000Y857000D03*
X81500Y837500D03*
X82500Y814000D03*
X48000Y816000D03*
X38000Y834000D03*
Y820000D03*
X46000Y848000D03*
Y834000D03*
X78300Y832600D03*
X77600Y849100D03*
X87000Y839500D03*
X48100Y853400D03*
X45600Y827500D03*
X57809Y852500D03*
X67000Y907300D03*
X52000Y867500D03*
X37500Y912000D03*
Y907500D03*
X77000Y871500D03*
X62500Y862000D03*
X61500Y876500D03*
X78000Y878500D03*
X77500Y907000D03*
X85500Y903000D03*
X78300Y893900D03*
X77000Y863000D03*
X83400Y878600D03*
X47000Y877600D03*
X40900Y901500D03*
X60900Y893000D03*
X54200Y926700D03*
X41000Y931899D03*
X86500Y932000D03*
X61500Y938500D03*
X81500Y940000D03*
X75500Y936500D03*
X69500Y939000D03*
X55500Y955500D03*
X56500Y940000D03*
X62500Y924500D03*
X70000Y914500D03*
Y925500D03*
X76500Y927000D03*
X85500Y915000D03*
X77500Y917000D03*
X58500Y912500D03*
X64000Y980500D03*
X87000Y997500D03*
X55500Y968000D03*
X76400Y999100D03*
X37500Y998000D03*
X37700Y991600D03*
X87000Y1064000D03*
X57500Y1050500D03*
X39300Y1105800D03*
X83500Y1072000D03*
Y1067000D03*
Y1076500D03*
X58500Y1104500D03*
X67302Y1133490D03*
X78292Y1148041D03*
X64500Y1165700D03*
X79044Y1144112D03*
X66000Y1149500D03*
X37500Y1118900D03*
X74000Y1132000D03*
X40000Y1136000D03*
Y1156000D03*
X77293Y1129729D03*
X56927Y1130027D03*
X58000Y1206000D03*
X46000Y1218000D03*
X60000Y1194000D03*
X61000Y1173000D03*
X54000Y1184000D03*
X44000Y1194000D03*
X42000Y1242000D03*
X50000Y1244000D03*
X42000Y1266000D03*
X58000Y1250000D03*
Y1222000D03*
X39500Y1231000D03*
X51800Y1231600D03*
X50100Y1261500D03*
X42000Y1290000D03*
X50000Y1318000D03*
X40000Y1278000D03*
Y1298000D03*
X44000Y1306000D03*
X58000Y1312000D03*
Y1292000D03*
Y1272000D03*
X52000Y1296300D03*
X61000Y1363500D03*
X52500Y1368500D03*
X39000Y1333500D03*
X44000Y1326000D03*
Y1340000D03*
X54000Y1330000D03*
X72000Y1360000D03*
X83800Y1365900D03*
X84000Y1352000D03*
X81500Y1382000D03*
Y1416500D03*
Y1404000D03*
X71800Y1373900D03*
X83800Y1391900D03*
X70500Y1378500D03*
X69400Y1402900D03*
X39500Y1407900D03*
X55600Y1381700D03*
X48900Y1390500D03*
X60900D03*
X56700Y1400100D03*
X60600Y1423600D03*
X68800Y1417800D03*
X58800Y1412400D03*
X49000Y1413300D03*
X72900Y1393600D03*
X74900Y1408800D03*
X75600Y1420300D03*
X61500Y1380000D03*
X86900Y1451000D03*
X70400Y1444500D03*
X79000Y1436400D03*
X76200Y1430700D03*
X66500Y1433500D03*
X53100Y1430700D03*
X42600Y1444200D03*
X49100Y1448400D03*
X68500Y1454600D03*
X74500Y1461800D03*
X72300Y1469800D03*
X59000Y1444500D03*
X77000Y1449000D03*
X59000Y1472000D03*
X58100Y1459300D03*
X83500Y1469500D03*
X85200Y1515000D03*
X58500Y1519000D03*
X72000Y1514000D03*
X53500Y1519000D03*
X63000Y1482300D03*
X42700Y1500000D03*
X72700Y1480500D03*
X46500Y1484900D03*
X64100Y1495400D03*
X73000Y1491200D03*
X43300Y1518500D03*
X49500Y1505000D03*
X45400Y1523800D03*
X76500Y1498500D03*
X85000Y1490000D03*
X81900Y1510200D03*
X54500Y1574000D03*
X73900Y1535900D03*
X80000Y1531600D03*
X54300Y1541200D03*
X59500Y1541000D03*
X57500Y1562000D03*
X57000Y1568500D03*
X46600Y1541100D03*
X45300Y1563600D03*
X45900Y1532800D03*
X37900Y1570000D03*
X38800Y1541700D03*
X38300Y1561800D03*
X44400Y1592100D03*
X38300Y1579600D03*
X71600Y1607700D03*
X50600Y1589300D03*
Y1582800D03*
Y1595300D03*
Y1601300D03*
X55300Y1601100D03*
Y1595100D03*
Y1582600D03*
Y1589100D03*
X68700Y1603900D03*
X55400Y1613300D03*
X58500Y1607700D03*
X43200Y1634800D03*
X59500Y1667000D03*
X70000Y1668000D03*
X75500Y1679000D03*
X86000D03*
Y1669000D03*
X76000Y1646000D03*
X86000D03*
X76000Y1634000D03*
X86000D03*
Y1659500D03*
X75500D03*
X54000Y1646500D03*
X64500Y1646000D03*
X57500Y1634500D03*
X64000Y1634000D03*
X64500Y1658500D03*
X53500Y1659000D03*
X37000Y1714000D03*
X42500Y1699500D03*
X44600Y1724400D03*
X44900Y1706800D03*
X56000Y1695000D03*
Y1704500D03*
Y1712500D03*
X55500Y1723500D03*
X69000Y1684500D03*
X80500D03*
X62500Y1691500D03*
X65000Y1724000D03*
X62500Y1709000D03*
X72500Y1717000D03*
Y1699000D03*
X62500Y1700000D03*
X60000Y1730000D03*
X86500Y1713610D03*
Y1700110D03*
Y1726000D03*
X48400Y1746900D03*
X41600D03*
X38800Y1775000D03*
X53000Y1750500D03*
X36700Y1764700D03*
X56500Y1769300D03*
X44900Y1740300D03*
X64500Y1758500D03*
X55500Y1735500D03*
X65000Y1735000D03*
X79000Y1766500D03*
X65000Y1749000D03*
Y1768000D03*
Y1742500D03*
X71500Y1760000D03*
X72500Y1733000D03*
X87000Y1774110D03*
X42000Y1784400D03*
X81000Y1802000D03*
X73000Y1813000D03*
X64500Y1821500D03*
Y1812000D03*
Y1801500D03*
X65000Y1790000D03*
X72500Y1830000D03*
X72000Y1798000D03*
X86500Y1793110D03*
X39179Y1792306D03*
X75000Y1882000D03*
X39700Y1869700D03*
X46700Y1857700D03*
X46500Y1850200D03*
X44500Y1833500D03*
X46500Y1844000D03*
Y1865500D03*
X71000Y1864500D03*
X75500Y1838500D03*
X63500Y1863000D03*
Y1856000D03*
X64000Y1844500D03*
Y1834000D03*
X73000Y1847000D03*
X85100Y1844500D03*
X85700Y1852300D03*
X45100Y1933400D03*
X54500Y1889500D03*
X63500Y1928000D03*
X61500Y1922500D03*
X46000Y1923000D03*
X54000Y1928500D03*
X36500Y1900500D03*
X63500Y1963000D03*
X63594Y1935500D03*
X61600Y1954700D03*
X41100Y1957500D03*
X55300Y1959100D03*
X43500Y1945000D03*
X49053Y1951747D03*
X135000Y50000D03*
Y70000D03*
X128500Y89000D03*
X118000Y54500D03*
X124000Y74500D03*
X105000Y55000D03*
Y45000D03*
X95000D03*
X115000D03*
X125000D03*
X135000D03*
X127000Y129000D03*
X137200Y123600D03*
X127700Y119200D03*
X128700Y104200D03*
X131000Y138100D03*
X118000Y124500D03*
X119000Y109500D03*
X118000Y142500D03*
X95000Y143000D03*
X105000D03*
X95000Y125000D03*
X105000D03*
X95000Y134000D03*
X129000Y160100D03*
X137900Y171400D03*
X131000Y150100D03*
X118000Y154500D03*
X95000Y155000D03*
X105000D03*
X131800Y289700D03*
X130900Y259100D03*
X114000Y296000D03*
X106000D03*
X96000D03*
X102000Y312000D03*
X104000Y304000D03*
X94000D03*
Y312000D03*
Y320000D03*
X111500Y390000D03*
X101300Y390100D03*
X105500Y390000D03*
X134000Y396000D03*
X118000D03*
Y386000D03*
X134000D03*
X105500Y406500D03*
X101500D03*
X107000Y426500D03*
X98000D03*
X102500D03*
X111200Y426400D03*
X110500Y406500D03*
X122500Y450500D03*
X117000Y449000D03*
X89800Y446000D03*
X136000Y447000D03*
X131000D03*
X91900Y410500D03*
X88500Y426500D03*
X134000Y404500D03*
X118000Y424000D03*
Y404000D03*
X130000Y432000D03*
X134000Y414000D03*
X118000D03*
X134000Y424000D03*
X129000Y485500D03*
X120000D03*
Y501500D03*
X110800Y482600D03*
X99800Y482000D03*
X110800Y488600D03*
X100000Y488000D03*
X110800Y500600D03*
X100000Y500000D03*
X129000Y501500D03*
X100000Y494000D03*
X110800Y494600D03*
X129000Y493500D03*
X120000D03*
X137000Y501500D03*
Y493000D03*
X136500Y485500D03*
X122500Y457500D03*
Y463500D03*
X121500Y475500D03*
X122500Y469500D03*
X117000Y455000D03*
Y460500D03*
Y466000D03*
Y471500D03*
X89800Y452900D03*
Y459000D03*
X111500Y473000D03*
X99500D03*
X89800Y464800D03*
X135500Y454000D03*
Y461000D03*
Y474500D03*
Y468000D03*
X130500Y454000D03*
Y461000D03*
Y468000D03*
Y474500D03*
X129000Y517500D03*
X100000Y512000D03*
X129000Y509500D03*
X110800Y512600D03*
X120000Y517500D03*
X100000Y506000D03*
X110800Y506600D03*
X120000Y509500D03*
Y523500D03*
X129000D03*
X137000Y510000D03*
X137500Y523500D03*
X100000Y519100D03*
X137500Y517500D03*
X117000Y530000D03*
X105300Y525200D03*
X90630Y602020D03*
X136500Y597000D03*
X131700Y571100D03*
X103100Y587600D03*
X87595Y581300D03*
X112800Y653500D03*
X106400Y648300D03*
X108200Y655825D03*
X137500Y682500D03*
X132110Y678353D03*
X88967Y659749D03*
X90674Y663367D03*
X121500Y683500D03*
X119576Y687008D03*
X120702Y690847D03*
X100600Y656600D03*
Y670600D03*
X134100Y674500D03*
X119000Y673300D03*
X87310Y676796D03*
X124800Y696600D03*
X129800Y696800D03*
X98000Y674327D03*
X102913Y673973D03*
X107113Y674001D03*
X108500Y695500D03*
X103500D03*
X115000Y704500D03*
X99001Y694866D03*
X128600Y669500D03*
X104000Y734000D03*
X125000D03*
X116500Y752000D03*
X125000Y751000D03*
X125500Y741500D03*
X130000Y736500D03*
X125000Y758500D03*
X120500Y732500D03*
X120000Y717500D03*
X107000Y802400D03*
Y798200D03*
X106882Y794201D03*
X123000Y808500D03*
X114500Y805500D03*
X123000Y800000D03*
X122500Y792500D03*
X114000Y800000D03*
X113500Y792500D03*
X130000Y800000D03*
X129500Y792500D03*
X121500Y783500D03*
X121000Y776000D03*
X129500Y782000D03*
X129000Y774500D03*
X115200Y784200D03*
X115000Y773200D03*
X121000Y767900D03*
X115217Y765517D03*
X111100Y788200D03*
X116402Y779402D03*
X95500Y841500D03*
X124500Y858000D03*
X123500Y842500D03*
Y816000D03*
X115000Y813000D03*
X129200Y830400D03*
X129800Y813500D03*
X124500Y825100D03*
X134500Y840500D03*
X90500Y831500D03*
X105763Y814263D03*
X137500Y903000D03*
X135500Y909000D03*
X124000D03*
X113500Y909500D03*
X103500D03*
X94000Y910500D03*
X116053Y903247D03*
X127000Y903000D03*
X90000Y893000D03*
X102500Y893500D03*
X117500Y893000D03*
X135000D03*
X134500Y885500D03*
X137500Y876500D03*
X125000Y868500D03*
X107000Y903000D03*
X124500Y876500D03*
X126000Y892500D03*
X96053Y903247D03*
X125500Y944000D03*
X105000Y958000D03*
X96500Y916500D03*
X107000Y918000D03*
X135000D03*
X135500Y927500D03*
X115000Y920000D03*
X125500D03*
X126000Y930000D03*
X115500D03*
X99000Y953000D03*
X88500Y940500D03*
X120000Y916000D03*
X126000Y954000D03*
X124618Y959244D03*
X110000Y949500D03*
X117529Y948844D03*
X93000Y925500D03*
X133500Y938000D03*
X134000Y990500D03*
X125000Y967000D03*
X130500Y966000D03*
X124000Y971500D03*
X117000Y1008500D03*
X105500Y996000D03*
X95500Y999000D03*
X106500Y1008500D03*
X104000Y1014000D03*
X119000Y975000D03*
X136500Y967000D03*
X108500Y964000D03*
Y971000D03*
X114800Y1005000D03*
X135000Y975500D03*
X122900Y1007400D03*
X91400Y1064100D03*
X95500Y1064000D03*
X97250Y1023500D03*
X88000Y1034500D03*
X110500Y1041500D03*
X111500Y1030000D03*
Y1020000D03*
X110500Y1064500D03*
Y1051000D03*
X103500Y1042000D03*
Y1028500D03*
X116500Y1049000D03*
Y1035500D03*
Y1062500D03*
X117500Y1023500D03*
X91500Y1093000D03*
X120000Y1108000D03*
Y1102000D03*
X115000Y1108500D03*
X110500Y1112000D03*
X103500Y1073500D03*
X104500Y1095000D03*
X116500Y1076000D03*
X109000Y1083500D03*
X89000Y1167400D03*
X101500Y1127500D03*
X106000D03*
X97000D03*
X97500Y1132500D03*
X121000Y1133000D03*
Y1147500D03*
X118500Y1166000D03*
X105000Y1196000D03*
X119300Y1191400D03*
X119500Y1177500D03*
Y1205500D03*
X92000Y1214500D03*
X104500Y1208000D03*
X94000Y1189000D03*
X91500Y1200000D03*
X99000Y1265500D03*
X119000Y1269000D03*
X117500Y1251000D03*
X112000Y1250500D03*
Y1244500D03*
X119300Y1245400D03*
Y1219400D03*
X119500Y1231500D03*
X124000Y1270000D03*
X104500Y1219500D03*
X92000Y1254000D03*
X103500Y1229000D03*
X92000Y1241500D03*
X103000Y1244900D03*
X91500Y1229000D03*
X122692Y1257808D03*
X124000Y1247600D03*
X91000Y1272500D03*
X99500Y1310000D03*
Y1294000D03*
X98000Y1282000D03*
X123800Y1283900D03*
X113800Y1287900D03*
X114000Y1274000D03*
X123800Y1311900D03*
X124000Y1298000D03*
X114000Y1318000D03*
X92000Y1295500D03*
X91500Y1314500D03*
X114500Y1296500D03*
X97800Y1327900D03*
X123800Y1337900D03*
X124000Y1324000D03*
X113800Y1331900D03*
X115800Y1363900D03*
X116000Y1350000D03*
X123800Y1365900D03*
X124000Y1352000D03*
X114500Y1370500D03*
X93800Y1353900D03*
X94000Y1340000D03*
Y1366000D03*
X90800Y1331200D03*
X105500Y1415000D03*
X99600Y1416500D03*
X100500Y1384500D03*
Y1389000D03*
X124000Y1376500D03*
X114000Y1376000D03*
X93800Y1379900D03*
Y1393200D03*
X93600Y1407100D03*
X97500Y1412000D03*
X89700Y1409700D03*
X110000Y1418000D03*
X89600Y1464000D03*
X137000Y1429200D03*
X126600Y1461500D03*
X133500Y1467100D03*
X132200Y1424800D03*
X94000Y1427800D03*
X87200Y1431900D03*
X87700Y1446500D03*
X87300Y1436000D03*
X95500Y1468000D03*
X103700Y1470300D03*
X113024Y1452079D03*
X117122Y1448001D03*
X117195Y1456070D03*
X121338Y1452021D03*
X117024Y1452000D03*
X87200Y1440000D03*
X95859Y1448359D03*
X99800Y1455600D03*
X101600Y1431000D03*
X109500Y1438000D03*
X98500Y1428400D03*
X122500Y1437509D03*
X117000Y1435200D03*
X133799Y1440699D03*
X93000Y1518700D03*
X94000Y1514000D03*
X87900Y1523400D03*
X124500Y1524000D03*
X91300Y1488600D03*
X97000Y1503100D03*
X93500Y1482700D03*
X99170Y1485790D03*
X134000Y1519500D03*
X119500Y1501000D03*
X108500Y1501500D03*
X114500Y1501800D03*
X104500Y1506000D03*
X135000Y1500500D03*
X130000Y1501000D03*
X125000Y1500500D03*
X129000Y1555500D03*
X111500Y1537500D03*
X122000Y1558000D03*
X114000Y1552000D03*
X122000D03*
X114000Y1558000D03*
X122000Y1564000D03*
X121800Y1569929D03*
X114000Y1564000D03*
X122000Y1576000D03*
X102000Y1544000D03*
Y1562000D03*
Y1550000D03*
Y1556000D03*
Y1568000D03*
X94000D03*
X116000Y1576000D03*
X115900Y1569700D03*
X129000Y1535000D03*
X136000Y1568000D03*
X94000Y1556000D03*
X129000Y1549000D03*
X122000Y1538000D03*
X136000Y1542000D03*
X122000Y1546000D03*
X129000Y1542500D03*
X136000Y1536000D03*
X114000Y1546000D03*
X128000Y1568000D03*
X136000Y1562000D03*
Y1555000D03*
X129000Y1562500D03*
X136000Y1548000D03*
X119000Y1529500D03*
X94000Y1550000D03*
Y1562000D03*
X136000Y1528000D03*
X108500Y1556500D03*
X122000Y1584000D03*
X116000D03*
Y1592000D03*
X122000D03*
X116000Y1600000D03*
X122000Y1612000D03*
X104000Y1605500D03*
X116000Y1612000D03*
X122000Y1600000D03*
X128000Y1606000D03*
X94500Y1605500D03*
X113500D03*
X117500Y1679000D03*
X125000D03*
X107500D03*
X117500Y1669000D03*
X127500D03*
X97000D03*
X107000D03*
X127000Y1646000D03*
X138000Y1634000D03*
X137500Y1659500D03*
X118000Y1646000D03*
X138000D03*
X117000Y1633500D03*
X127500Y1633000D03*
Y1659500D03*
X117500D03*
X108000Y1646000D03*
X106000Y1634000D03*
X107000Y1659500D03*
X96000Y1646000D03*
X96500Y1634000D03*
X97000Y1659500D03*
X122000Y1685500D03*
X91000Y1685000D03*
X103000D03*
X112500D03*
X108500Y1727000D03*
X98500Y1717000D03*
Y1696500D03*
X99000Y1707000D03*
X97500Y1679500D03*
X109500Y1719500D03*
X110000Y1709500D03*
X109500Y1699000D03*
X119500Y1710110D03*
Y1696610D03*
Y1725110D03*
X111500Y1768500D03*
X117500Y1732000D03*
X119500Y1760000D03*
X97500Y1775500D03*
X108268Y1777300D03*
X119500Y1747110D03*
X138000Y1824000D03*
X110500Y1801000D03*
X88500Y1785000D03*
X97500Y1796000D03*
X98000Y1786000D03*
X107768Y1789110D03*
X120000Y1811500D03*
X119500Y1796500D03*
X114000Y1843500D03*
X97000Y1850500D03*
X99500Y1862500D03*
X106500D03*
X114500D03*
X122500D03*
X120500Y1836500D03*
Y1850500D03*
X108500Y1851610D03*
X116948Y1892000D03*
X124500Y1892403D03*
X132000Y1892000D03*
X97500Y1901000D03*
X93000Y1884500D03*
X118000Y1922000D03*
X184000Y55500D03*
X174000D03*
X164000D03*
X153000Y90500D03*
X154000Y75500D03*
X145000Y45000D03*
X155000D03*
X165000D03*
X175000D03*
X185000D03*
X180500Y112000D03*
X186000Y143000D03*
X187500Y130500D03*
X167000D03*
X176000Y131000D03*
X165500Y95500D03*
X174500Y143500D03*
X171500Y105500D03*
X170500Y120500D03*
X146500Y131859D03*
X154000Y105500D03*
X147600Y150900D03*
X165300Y145200D03*
X173500Y151500D03*
X185500D03*
X138800Y162100D03*
X141300Y298100D03*
X182000Y296000D03*
X172000D03*
X162000D03*
X142000Y291000D03*
X187500Y338000D03*
X180850Y348800D03*
X184500Y325500D03*
X143400Y318700D03*
X174000Y316000D03*
X164000D03*
X172000Y310000D03*
X182000D03*
X184000Y303000D03*
X176000Y302000D03*
X166000D03*
X143300Y343400D03*
X151300Y298200D03*
X154000Y355500D03*
X188500Y364100D03*
X188300Y368600D03*
X181800Y369000D03*
X181100Y364050D03*
X150000Y386000D03*
Y396000D03*
X186600Y425750D03*
X161600Y445900D03*
X161900Y451600D03*
X174500Y432000D03*
X162000D03*
X145500Y427000D03*
X142000Y432000D03*
X150000Y404000D03*
Y414000D03*
Y424000D03*
X186500Y498000D03*
X144000Y501500D03*
X173600Y498800D03*
X169200Y482800D03*
X157100Y500000D03*
X144000Y493500D03*
Y486182D03*
X162000Y457600D03*
X161900Y463300D03*
X188500Y474500D03*
X186500Y513500D03*
X173700Y513900D03*
X144000Y517500D03*
X173500Y506000D03*
X186500D03*
Y519000D03*
X174900Y523300D03*
X156800Y515400D03*
Y506900D03*
X144600Y533800D03*
X147500Y551500D03*
X182600Y546900D03*
X179300Y530000D03*
X184003Y536497D03*
X180500Y595000D03*
X171600Y595400D03*
X145500Y604000D03*
X141800Y559250D03*
X150500Y596000D03*
X153500Y574359D03*
X140700Y576600D03*
X152700Y618803D03*
X146000Y641400D03*
X170349Y619949D03*
X166500Y640000D03*
X167300Y653800D03*
X159700Y652000D03*
X175800Y617635D03*
X164950Y615700D03*
X180500Y627771D03*
X165600Y630269D03*
X141800Y676300D03*
X151432Y661741D03*
X148995Y658568D03*
X185000Y673500D03*
X188100Y689100D03*
X176000Y679000D03*
Y665500D03*
X162300Y659100D03*
X183500Y698000D03*
X184700Y663900D03*
X165500Y677500D03*
X152000Y695688D03*
X173500Y740500D03*
X184500Y708500D03*
X181000Y729000D03*
Y715500D03*
X182500Y758500D03*
Y745000D03*
X172000Y757500D03*
X181500Y738500D03*
X169100Y722100D03*
X169000Y795500D03*
X163500Y805500D03*
X178000Y797500D03*
X187900Y785300D03*
X175000Y786500D03*
X173500Y777500D03*
Y764000D03*
X181700Y768400D03*
X165000Y786000D03*
X171500Y819500D03*
X177500Y812000D03*
Y826500D03*
X145500Y856500D03*
X140500Y846500D03*
X157500Y858000D03*
X185000Y843500D03*
X145500Y885000D03*
X143000Y910500D03*
X146000Y893000D03*
X184500Y879000D03*
Y865500D03*
X154700Y909700D03*
X156300Y877200D03*
X156500Y889000D03*
X187000Y891000D03*
X153500Y941000D03*
X141000Y938500D03*
X144000Y919500D03*
Y929000D03*
X154500Y926500D03*
X185000Y917500D03*
X182000Y950500D03*
X174000Y1012400D03*
X184000Y987500D03*
X146800Y1018900D03*
X143900Y1022700D03*
X166300Y1021300D03*
X182500Y1041500D03*
X183500Y1065500D03*
X182000Y1029500D03*
Y1016000D03*
X171000Y1046000D03*
Y1032500D03*
X175000Y1059000D03*
X160500Y1053500D03*
X181000Y1051000D03*
X164700Y1033600D03*
X176000Y1018500D03*
X171000Y1068000D03*
X166000Y1080000D03*
X173000Y1082000D03*
X165000Y1097000D03*
X181000Y1098500D03*
X175000Y1072500D03*
X160500Y1067000D03*
X187500Y1103500D03*
Y1090000D03*
X170000Y1103000D03*
Y1089500D03*
X157000Y1101500D03*
X159500Y1087500D03*
X181000Y1112500D03*
Y1079500D03*
X154600Y1111000D03*
X158500Y1075800D03*
X158595Y1110789D03*
X155000Y1130500D03*
Y1125000D03*
Y1120000D03*
X147500Y1165500D03*
X177102Y1129800D03*
X171502Y1129547D03*
X147500Y1186000D03*
X178644Y1202519D03*
X163344Y1181200D03*
X161500Y1227500D03*
X147500Y1221500D03*
X146500Y1241500D03*
X147000Y1265500D03*
X183500Y1241500D03*
X165000Y1264500D03*
X147500Y1288000D03*
Y1311000D03*
X164500Y1299500D03*
X147500Y1332000D03*
X147000Y1348000D03*
X147500Y1366500D03*
X171000Y1407500D03*
X147000Y1377000D03*
X146500Y1417619D03*
X148300Y1465000D03*
X173375Y1432500D03*
X149686Y1460007D03*
X152500Y1456000D03*
X156000Y1447500D03*
X174500Y1503500D03*
Y1509500D03*
X174000Y1515500D03*
Y1522000D03*
X147500Y1505000D03*
X138500Y1504500D03*
X148000Y1550000D03*
X170000Y1541000D03*
X148000Y1558000D03*
Y1528000D03*
Y1542000D03*
X168500Y1533500D03*
X170000Y1555000D03*
X161400Y1543500D03*
X150000Y1576000D03*
X156000Y1570000D03*
X154000Y1564000D03*
X170000Y1548500D03*
X169500Y1561500D03*
X161300Y1563100D03*
X148000Y1564000D03*
X156000Y1576000D03*
X168500Y1526000D03*
X166898Y1567102D03*
X150000Y1570000D03*
X143518Y1540000D03*
X157000Y1528000D03*
X156000Y1582000D03*
X156500Y1591000D03*
X150500Y1582000D03*
Y1591000D03*
X172000Y1606000D03*
X182500Y1599400D03*
X146000Y1612000D03*
X148000Y1606000D03*
X182500Y1592000D03*
X164000Y1606000D03*
X156500Y1600000D03*
X156000Y1606000D03*
X150500Y1600000D03*
X138500Y1606000D03*
X182500Y1584500D03*
X141500Y1673000D03*
X176000Y1646000D03*
X166000D03*
X158000D03*
X148000D03*
X176000Y1632000D03*
X178000Y1659500D03*
X167500Y1632500D03*
X170000Y1659500D03*
X149000Y1632500D03*
X159000D03*
Y1659500D03*
X148500Y1660000D03*
X139000Y1696500D03*
Y1712500D03*
X138500Y1727500D03*
X181500Y1716500D03*
X158500D03*
X167500Y1716000D03*
X182000Y1726000D03*
Y1704000D03*
X168500Y1705000D03*
X158500D03*
X184500Y1696500D03*
X163000Y1697000D03*
X174268Y1697110D03*
X152000D03*
Y1710610D03*
Y1725610D03*
X185000Y1738500D03*
X183600Y1765100D03*
X169000Y1781500D03*
X162500Y1773000D03*
X152500Y1771110D03*
X173268Y1776000D03*
X139000Y1800500D03*
X156500Y1782000D03*
X155500Y1798500D03*
X166500Y1798000D03*
X179000Y1798500D03*
X185500Y1804500D03*
X186000Y1790000D03*
X162000D03*
X172768Y1790110D03*
X152000D03*
X144500Y1877000D03*
X139000Y1851000D03*
X138500Y1839500D03*
X185000Y1852500D03*
X161500D03*
X183100Y1838300D03*
X160500Y1877500D03*
X173000Y1852610D03*
X151500Y1851110D03*
X161000Y1901500D03*
X194000Y55500D03*
X195000Y45000D03*
X200000Y55000D03*
Y65000D03*
Y75000D03*
Y85000D03*
X190500Y105000D03*
X189500Y120000D03*
X200000Y100000D03*
Y120000D03*
Y140000D03*
X191900Y167700D03*
X191700Y186500D03*
X201089Y181700D03*
X197500Y151500D03*
X191900Y244600D03*
X191800Y234900D03*
Y221100D03*
X191600Y206900D03*
X201500Y208000D03*
X201000Y222500D03*
X200500Y235000D03*
Y195900D03*
X202000Y295000D03*
Y274000D03*
Y254000D03*
X201089Y282600D03*
X202000Y264000D03*
Y340000D03*
Y328000D03*
X201089Y305500D03*
Y315500D03*
X201500Y397500D03*
Y378000D03*
X202000Y366500D03*
Y353000D03*
X192600Y392600D03*
X192471Y397355D03*
X201089Y388400D03*
X200500Y437500D03*
X201000Y430500D03*
X201089Y407000D03*
X200000Y420500D03*
X192400Y401900D03*
X192300Y410950D03*
X192409Y417655D03*
X190239Y447449D03*
X195600Y447500D03*
X192000Y490000D03*
Y498000D03*
X200300Y498100D03*
X199500Y489400D03*
X189900Y467500D03*
Y460500D03*
X190400Y453500D03*
X195000Y467500D03*
X194500Y474500D03*
X195000Y460500D03*
X195500Y453500D03*
X192007Y482593D03*
X192000Y513500D03*
Y506000D03*
X190200Y523400D03*
X201089Y523500D03*
X193600Y519100D03*
X200100Y513600D03*
X199800Y506000D03*
X201200Y519200D03*
X201500Y544500D03*
X201089Y529500D03*
X201500Y552500D03*
X192400Y529400D03*
X191900Y538200D03*
X201500Y535000D03*
X192000Y543500D03*
X190500Y550500D03*
X202000Y578000D03*
Y586000D03*
Y595000D03*
X193700D03*
X194400Y586000D03*
X201089Y558000D03*
X201500Y564000D03*
X201089Y570600D03*
X202000Y607500D03*
X196500Y641500D03*
X192600Y633000D03*
X201500Y621500D03*
X202000Y650500D03*
X194000Y628500D03*
Y615000D03*
X192500Y645000D03*
X195000Y670000D03*
X197500Y685000D03*
X197000Y704000D03*
X202000Y676500D03*
X192500Y658500D03*
X191500Y692500D03*
X193100Y679000D03*
X196000Y718500D03*
X195500Y739000D03*
X197500Y753000D03*
X202000Y710000D03*
Y740500D03*
X191500Y724000D03*
Y710500D03*
Y746500D03*
X196000Y789500D03*
X196500Y797000D03*
X202000Y765000D03*
Y786000D03*
Y807500D03*
X191500Y760000D03*
X194500Y782500D03*
Y769000D03*
X196800Y828500D03*
X197000Y815000D03*
X190000Y823500D03*
X190500Y831000D03*
X201500Y835500D03*
X192500Y853000D03*
Y839500D03*
X192000Y879000D03*
Y865500D03*
X194000Y907000D03*
Y893500D03*
X192000Y934500D03*
Y921000D03*
Y962000D03*
Y948500D03*
X192500Y985500D03*
Y972000D03*
X195500Y1001000D03*
X190000Y1052000D03*
X195500Y1014500D03*
X193500Y1042500D03*
Y1029000D03*
X195000Y1061000D03*
Y1086500D03*
X194500Y1100500D03*
X195000Y1074500D03*
X201000Y1106500D03*
Y1093000D03*
X191800Y1280900D03*
X192500Y1543500D03*
Y1554000D03*
Y1533000D03*
Y1562500D03*
X196500Y1586000D03*
Y1595000D03*
X192500Y1617000D03*
Y1626500D03*
Y1634000D03*
Y1670500D03*
Y1664000D03*
X198500Y1713500D03*
X198000Y1691500D03*
X197500Y1776500D03*
X198000Y1754000D03*
Y1735500D03*
Y1818500D03*
X197500Y1800500D03*
X198500Y1859500D03*
X198000Y1838500D03*
X195000Y1874000D03*
X200000Y1882000D03*
X201500Y1900500D03*
X190500Y1924000D03*
X201000Y1923000D03*
X195500Y1905000D03*
G54D22*
G01X-430254Y-152763D02*
Y-135263D01*
G01X-421958D02*
X-430254Y-146055D01*
G01X-420648Y-152763D02*
X-426543Y-141097D01*
G01X-412973Y-152763D02*
Y-135263D01*
X-402929Y-152763D01*
Y-135263D01*
G01X-390451Y-152763D02*
X-392198Y-152471D01*
X-393726Y-151305D01*
X-395036Y-149555D01*
X-395910Y-147513D01*
X-396346Y-145180D01*
Y-142846D01*
X-395910Y-140513D01*
X-395036Y-138471D01*
X-393726Y-136722D01*
X-392198Y-135555D01*
X-390451Y-135263D01*
X-388705Y-135555D01*
X-387176Y-136722D01*
X-385866Y-138471D01*
X-384992Y-140513D01*
X-384556Y-142846D01*
Y-145180D01*
X-384992Y-147513D01*
X-385866Y-149555D01*
X-387176Y-151305D01*
X-388705Y-152471D01*
X-390451Y-152763D01*
G01X-377536D02*
X-368366Y-135263D01*
G01X-377536D02*
X-368366Y-152763D01*
G01X-362001Y-158596D02*
X-348901D01*
G01X-342099Y-152763D02*
Y-135263D01*
X-333803D01*
G01X-336859Y-143721D02*
X-342099D01*
G01X-325910Y-152763D02*
X-320451Y-135263D01*
X-314992Y-152763D01*
G01X-316958Y-146638D02*
X-323945D01*
G01X-307973Y-152763D02*
Y-135263D01*
X-297929Y-152763D01*
Y-135263D01*
G01X-263148Y-136722D02*
X-264458Y-135846D01*
X-265986Y-135263D01*
X-267733D01*
X-269698Y-136138D01*
X-271226Y-137596D01*
X-272318Y-139347D01*
X-273191Y-142263D01*
X-273410Y-144888D01*
X-272973Y-147513D01*
X-272318Y-149263D01*
X-271008Y-151013D01*
X-269479Y-152180D01*
X-267951Y-152763D01*
X-266423D01*
X-264894Y-152180D01*
X-263584Y-151305D01*
X-262492Y-150139D01*
G01X-250451Y-152763D02*
X-252198Y-152471D01*
X-253726Y-151305D01*
X-255036Y-149555D01*
X-255910Y-147513D01*
X-256346Y-145180D01*
Y-142846D01*
X-255910Y-140513D01*
X-255036Y-138471D01*
X-253726Y-136722D01*
X-252198Y-135555D01*
X-250451Y-135263D01*
X-248705Y-135555D01*
X-247176Y-136722D01*
X-245866Y-138471D01*
X-244992Y-140513D01*
X-244556Y-142846D01*
Y-145180D01*
X-244992Y-147513D01*
X-245866Y-149555D01*
X-247176Y-151305D01*
X-248705Y-152471D01*
X-250451Y-152763D01*
G01X-237973D02*
Y-135263D01*
X-227929Y-152763D01*
Y-135263D01*
G01X-215451D02*
Y-152763D01*
G01X-220473Y-135263D02*
X-210429D01*
G01X-202318Y-152763D02*
Y-135263D01*
X-196859D01*
X-195113Y-136138D01*
X-194021Y-137305D01*
X-193584Y-139638D01*
X-194021Y-141972D01*
X-195331Y-143430D01*
X-196859Y-144305D01*
X-202318D01*
G01X-196859D02*
X-193584Y-152763D01*
G01X-180451D02*
X-182198Y-152471D01*
X-183726Y-151305D01*
X-185036Y-149555D01*
X-185910Y-147513D01*
X-186346Y-145180D01*
Y-142846D01*
X-185910Y-140513D01*
X-185036Y-138471D01*
X-183726Y-136722D01*
X-182198Y-135555D01*
X-180451Y-135263D01*
X-178705Y-135555D01*
X-177176Y-136722D01*
X-175866Y-138471D01*
X-174992Y-140513D01*
X-174556Y-142846D01*
Y-145180D01*
X-174992Y-147513D01*
X-175866Y-149555D01*
X-177176Y-151305D01*
X-178705Y-152471D01*
X-180451Y-152763D01*
G01X-167318Y-135263D02*
Y-152763D01*
X-158584D01*
G01X-126205Y-143430D02*
X-125331Y-142555D01*
X-124676Y-141097D01*
X-124239Y-139054D01*
X-124676Y-137305D01*
X-125549Y-136138D01*
X-127078Y-135263D01*
X-132973D01*
Y-152763D01*
X-125768D01*
X-124239Y-151597D01*
X-123366Y-149846D01*
X-122929Y-147805D01*
X-123366Y-145763D01*
X-124676Y-144013D01*
X-126205Y-143430D01*
X-132973D01*
G01X-110451Y-152763D02*
X-112198Y-152471D01*
X-113726Y-151305D01*
X-115036Y-149555D01*
X-115910Y-147513D01*
X-116346Y-145180D01*
Y-142846D01*
X-115910Y-140513D01*
X-115036Y-138471D01*
X-113726Y-136722D01*
X-112198Y-135555D01*
X-110451Y-135263D01*
X-108705Y-135555D01*
X-107176Y-136722D01*
X-105866Y-138471D01*
X-104992Y-140513D01*
X-104556Y-142846D01*
Y-145180D01*
X-104992Y-147513D01*
X-105866Y-149555D01*
X-107176Y-151305D01*
X-108705Y-152471D01*
X-110451Y-152763D01*
G01X-98410D02*
X-92951Y-135263D01*
X-87492Y-152763D01*
G01X-89458Y-146638D02*
X-96445D01*
G01X-79818Y-152763D02*
Y-135263D01*
X-74359D01*
X-72613Y-136138D01*
X-71521Y-137305D01*
X-71084Y-139638D01*
X-71521Y-141972D01*
X-72831Y-143430D01*
X-74359Y-144305D01*
X-79818D01*
G01X-74359D02*
X-71084Y-152763D01*
G01X-62754D02*
Y-135263D01*
X-58388D01*
X-56641Y-136138D01*
X-55331Y-137305D01*
X-54239Y-139054D01*
X-53366Y-141097D01*
X-53148Y-144013D01*
X-53366Y-146930D01*
X-54239Y-148972D01*
X-55331Y-150722D01*
X-56641Y-151888D01*
X-58388Y-152763D01*
X-62754D01*
G01X-282378Y-107763D02*
Y-90263D01*
X-276701Y-104846D01*
X-271024Y-90263D01*
Y-107763D01*
G01X-259201D02*
X-260511Y-107471D01*
X-261821Y-106305D01*
X-262695Y-104263D01*
X-263131Y-101930D01*
X-262695Y-99596D01*
X-261821Y-97555D01*
X-260511Y-96388D01*
X-259201Y-96097D01*
X-257891Y-96388D01*
X-256581Y-97555D01*
X-255708Y-99596D01*
X-255489Y-101930D01*
X-255708Y-104263D01*
X-256581Y-106305D01*
X-257891Y-107471D01*
X-259201Y-107763D01*
G01X-237771Y-90263D02*
Y-107763D01*
G01Y-105139D02*
X-238644Y-106597D01*
X-239955Y-107471D01*
X-241483Y-107763D01*
X-243229Y-107180D01*
X-244539Y-105722D01*
X-245413Y-103972D01*
X-245631Y-101930D01*
X-245413Y-99888D01*
X-244539Y-98138D01*
X-243229Y-96680D01*
X-241483Y-96097D01*
X-239955Y-96388D01*
X-238863Y-96972D01*
X-237771Y-98138D01*
G01X-227476Y-99888D02*
X-220489D01*
X-221144Y-97846D01*
X-222236Y-96680D01*
X-223764Y-96097D01*
X-225293Y-96388D01*
X-226603Y-97263D01*
X-227476Y-99305D01*
X-227913Y-101055D01*
Y-102805D01*
X-227476Y-104555D01*
X-226384Y-106305D01*
X-225074Y-107471D01*
X-223546Y-107763D01*
X-222018Y-107180D01*
X-220489Y-105430D01*
G01X-206701Y-107763D02*
Y-90263D01*
G01X-14018Y-107763D02*
Y-90263D01*
X-8778D01*
X-7031Y-91138D01*
X-5721Y-93180D01*
X-5284Y-95513D01*
X-5721Y-97846D01*
X-6813Y-99596D01*
X-8778Y-100472D01*
X-14018D01*
G01X12652Y-91722D02*
X11342Y-90846D01*
X9814Y-90263D01*
X8067D01*
X6102Y-91138D01*
X4574Y-92596D01*
X3482Y-94347D01*
X2609Y-97263D01*
X2390Y-99888D01*
X2827Y-102513D01*
X3482Y-104263D01*
X4792Y-106013D01*
X6321Y-107180D01*
X7849Y-107763D01*
X9377D01*
X10906Y-107180D01*
X12216Y-106305D01*
X13308Y-105139D01*
G01X27095Y-98430D02*
X27969Y-97555D01*
X28624Y-96097D01*
X29061Y-94054D01*
X28624Y-92305D01*
X27751Y-91138D01*
X26222Y-90263D01*
X20327D01*
Y-107763D01*
X27532D01*
X29061Y-106597D01*
X29934Y-104846D01*
X30371Y-102805D01*
X29934Y-100763D01*
X28624Y-99013D01*
X27095Y-98430D01*
X20327D01*
G01X36299Y-113596D02*
X49399D01*
G01X55327Y-107763D02*
Y-90263D01*
X65371Y-107763D01*
Y-90263D01*
G01X77849Y-107763D02*
X76102Y-107471D01*
X74574Y-106305D01*
X73264Y-104555D01*
X72390Y-102513D01*
X71954Y-100180D01*
Y-97846D01*
X72390Y-95513D01*
X73264Y-93471D01*
X74574Y-91722D01*
X76102Y-90555D01*
X77849Y-90263D01*
X79595Y-90555D01*
X81124Y-91722D01*
X82434Y-93471D01*
X83308Y-95513D01*
X83744Y-97846D01*
Y-100180D01*
X83308Y-102513D01*
X82434Y-104555D01*
X81124Y-106305D01*
X79595Y-107471D01*
X77849Y-107763D01*
G01X-901Y-152763D02*
Y-135263D01*
X-3521Y-138763D01*
G01Y-152763D02*
X1719D01*
G01X12451Y-138180D02*
X13761Y-136430D01*
X15289Y-135555D01*
X17036Y-135263D01*
X19219Y-135846D01*
X20747Y-137305D01*
X21184Y-139054D01*
X20966Y-140805D01*
X20092Y-142263D01*
X15726Y-145180D01*
X13761Y-147221D01*
X12451Y-150139D01*
X12014Y-152763D01*
X21184D01*
G01X36719D02*
Y-135263D01*
X28640Y-147805D01*
X39558D01*
G01X46796Y-149263D02*
X48105Y-151305D01*
X49852Y-152471D01*
X51817Y-152763D01*
X53564Y-152471D01*
X55311Y-151013D01*
X56402Y-149263D01*
X56621Y-147513D01*
X56184Y-145472D01*
X54656Y-144013D01*
X53127Y-143430D01*
X51162D01*
G01X53127D02*
X54437Y-142555D01*
X55529Y-141097D01*
X55966Y-139347D01*
X55529Y-137596D01*
X54437Y-136138D01*
X52472Y-135263D01*
X50507Y-135555D01*
X48542Y-136722D01*
G01X64296Y-149263D02*
X65605Y-151305D01*
X67352Y-152471D01*
X69317Y-152763D01*
X71064Y-152471D01*
X72811Y-151013D01*
X73902Y-149263D01*
X74121Y-147513D01*
X73684Y-145472D01*
X72156Y-144013D01*
X70627Y-143430D01*
X68662D01*
G01X70627D02*
X71937Y-142555D01*
X73029Y-141097D01*
X73466Y-139347D01*
X73029Y-137596D01*
X71937Y-136138D01*
X69972Y-135263D01*
X68007Y-135555D01*
X66042Y-136722D01*
G01X128690Y-90263D02*
X134149Y-107763D01*
X139608Y-90263D01*
G01X156016Y-107763D02*
X147282D01*
Y-90263D01*
X156016D01*
G01X152522Y-98721D02*
X147282D01*
G01X164782Y-107763D02*
Y-90263D01*
X170241D01*
X171987Y-91138D01*
X173079Y-92305D01*
X173516Y-94638D01*
X173079Y-96972D01*
X171769Y-98430D01*
X170241Y-99305D01*
X164782D01*
G01X170241D02*
X173516Y-107763D01*
G01X186649Y-108346D02*
X186212Y-108055D01*
Y-107471D01*
X186649Y-107180D01*
X187086Y-107471D01*
Y-108055D01*
X186649Y-108346D01*
G01X147501Y-138180D02*
X148811Y-136430D01*
X150339Y-135555D01*
X152086Y-135263D01*
X154269Y-135846D01*
X155797Y-137305D01*
X156234Y-139054D01*
X156016Y-140805D01*
X155142Y-142263D01*
X150776Y-145180D01*
X148811Y-147221D01*
X147501Y-150139D01*
X147064Y-152763D01*
X156234D01*
G01X163690D02*
X169149Y-135263D01*
X174608Y-152763D01*
G01X172642Y-146638D02*
X165655D01*
G01X253482Y-90263D02*
Y-107763D01*
X262216D01*
G01X279279D02*
Y-96097D01*
G01Y-98138D02*
X278406Y-96972D01*
X277095Y-96388D01*
X275567Y-96097D01*
X274039Y-96680D01*
X272729Y-97846D01*
X271855Y-99596D01*
X271419Y-101930D01*
X271855Y-104263D01*
X272729Y-106013D01*
X274039Y-107180D01*
X275567Y-107763D01*
X277095Y-107471D01*
X278406Y-106597D01*
X279279Y-105430D01*
G01X288264Y-113013D02*
X289574Y-113596D01*
X291321Y-113013D01*
X292412Y-111847D01*
X293286Y-110388D01*
X294595Y-105722D01*
X297434Y-96097D01*
G01X290447D02*
X294595Y-105722D01*
G01X307074Y-99888D02*
X314061D01*
X313406Y-97846D01*
X312314Y-96680D01*
X310786Y-96097D01*
X309257Y-96388D01*
X307947Y-97263D01*
X307074Y-99305D01*
X306637Y-101055D01*
Y-102805D01*
X307074Y-104555D01*
X308166Y-106305D01*
X309476Y-107471D01*
X311004Y-107763D01*
X312532Y-107180D01*
X314061Y-105430D01*
G01X324792Y-107763D02*
Y-96097D01*
G01Y-98430D02*
X325884Y-97263D01*
X326976Y-96388D01*
X328504Y-96097D01*
X329595Y-96388D01*
X330906Y-97263D01*
G01X342074Y-105722D02*
X343166Y-106888D01*
X344694Y-107763D01*
X346004D01*
X347314Y-107180D01*
X348187Y-106305D01*
X348624Y-105139D01*
X348406Y-103388D01*
X347532Y-102513D01*
X343602Y-100763D01*
X342729Y-98721D01*
X343166Y-97263D01*
X344039Y-96388D01*
X345349Y-96097D01*
X346659Y-96388D01*
X347969Y-97263D01*
G01X314716Y-135263D02*
Y-152763D01*
X305982D01*
G01X290229D02*
Y-135263D01*
X298308Y-147805D01*
X287390D01*
G01X404346Y-107763D02*
Y-90263D01*
X408712D01*
X410459Y-91138D01*
X411769Y-92305D01*
X412861Y-94054D01*
X413734Y-96097D01*
X413952Y-99013D01*
X413734Y-101930D01*
X412861Y-103972D01*
X411769Y-105722D01*
X410459Y-106888D01*
X408712Y-107763D01*
X404346D01*
G01X423374Y-99888D02*
X430361D01*
X429706Y-97846D01*
X428614Y-96680D01*
X427086Y-96097D01*
X425557Y-96388D01*
X424247Y-97263D01*
X423374Y-99305D01*
X422937Y-101055D01*
Y-102805D01*
X423374Y-104555D01*
X424466Y-106305D01*
X425776Y-107471D01*
X427304Y-107763D01*
X428832Y-107180D01*
X430361Y-105430D01*
G01X440874Y-105722D02*
X441966Y-106888D01*
X443494Y-107763D01*
X444804D01*
X446114Y-107180D01*
X446987Y-106305D01*
X447424Y-105139D01*
X447206Y-103388D01*
X446332Y-102513D01*
X442402Y-100763D01*
X441529Y-98721D01*
X441966Y-97263D01*
X442839Y-96388D01*
X444149Y-96097D01*
X445459Y-96388D01*
X446769Y-97263D01*
G01X461649Y-96097D02*
Y-107763D01*
G01Y-91430D02*
X461212Y-91138D01*
Y-90555D01*
X461649Y-90263D01*
X462086Y-90555D01*
Y-91138D01*
X461649Y-91430D01*
G01X476092Y-112138D02*
X477621Y-113305D01*
X479367Y-113596D01*
X480895Y-113305D01*
X482206Y-111847D01*
X483079Y-109805D01*
Y-96097D01*
G01Y-98430D02*
X482206Y-97263D01*
X480895Y-96388D01*
X479367Y-96097D01*
X477621Y-96680D01*
X476529Y-97846D01*
X475655Y-99888D01*
X475219Y-101930D01*
X475437Y-103680D01*
X476311Y-105722D01*
X477621Y-107180D01*
X479367Y-107763D01*
X480677Y-107471D01*
X482206Y-106305D01*
X483079Y-105139D01*
G01X492937Y-107763D02*
Y-96097D01*
G01Y-99013D02*
X493811Y-97555D01*
X495121Y-96388D01*
X496867Y-96097D01*
X498395Y-96388D01*
X499706Y-97555D01*
X500361Y-99596D01*
Y-107763D01*
G01X510874Y-99888D02*
X517861D01*
X517206Y-97846D01*
X516114Y-96680D01*
X514586Y-96097D01*
X513057Y-96388D01*
X511747Y-97263D01*
X510874Y-99305D01*
X510437Y-101055D01*
Y-102805D01*
X510874Y-104555D01*
X511966Y-106305D01*
X513276Y-107471D01*
X514804Y-107763D01*
X516332Y-107180D01*
X517861Y-105430D01*
G01X528592Y-107763D02*
Y-96097D01*
G01Y-98430D02*
X529684Y-97263D01*
X530776Y-96388D01*
X532304Y-96097D01*
X533395Y-96388D01*
X534706Y-97263D01*
G01X429722Y-152763D02*
Y-135263D01*
X435399Y-149846D01*
X441076Y-135263D01*
Y-152763D01*
G01X452899D02*
X451152Y-152471D01*
X449624Y-151305D01*
X448314Y-149555D01*
X447440Y-147513D01*
X447004Y-145180D01*
Y-142846D01*
X447440Y-140513D01*
X448314Y-138471D01*
X449624Y-136722D01*
X451152Y-135555D01*
X452899Y-135263D01*
X454645Y-135555D01*
X456174Y-136722D01*
X457484Y-138471D01*
X458358Y-140513D01*
X458794Y-142846D01*
Y-145180D01*
X458358Y-147513D01*
X457484Y-149555D01*
X456174Y-151305D01*
X454645Y-152471D01*
X452899Y-152763D01*
G01X465814Y-150430D02*
X467561Y-151888D01*
X469526Y-152763D01*
X471272D01*
X473019Y-151888D01*
X474329Y-150430D01*
X474984Y-148388D01*
X474547Y-146347D01*
X473456Y-144596D01*
X471491Y-143430D01*
X468871Y-142846D01*
X467342Y-141680D01*
X466687Y-139638D01*
X467124Y-137596D01*
X468216Y-136138D01*
X469744Y-135263D01*
X471272D01*
X472801Y-135846D01*
X474111Y-137305D01*
G01X483314Y-150430D02*
X485061Y-151888D01*
X487026Y-152763D01*
X488772D01*
X490519Y-151888D01*
X491829Y-150430D01*
X492484Y-148388D01*
X492047Y-146347D01*
X490956Y-144596D01*
X488991Y-143430D01*
X486371Y-142846D01*
X484842Y-141680D01*
X484187Y-139638D01*
X484624Y-137596D01*
X485716Y-136138D01*
X487244Y-135263D01*
X488772D01*
X490301Y-135846D01*
X491611Y-137305D01*
G01X509766Y-152763D02*
X501032D01*
Y-135263D01*
X509766D01*
G01X506272Y-143721D02*
X501032D01*
G01X575349Y-152763D02*
Y-135263D01*
X572729Y-138763D01*
G01Y-152763D02*
X577969D01*
G01X588701Y-138180D02*
X590011Y-136430D01*
X591539Y-135555D01*
X593286Y-135263D01*
X595469Y-135846D01*
X596997Y-137305D01*
X597434Y-139054D01*
X597216Y-140805D01*
X596342Y-142263D01*
X591976Y-145180D01*
X590011Y-147221D01*
X588701Y-150139D01*
X588264Y-152763D01*
X597434D01*
G01X606419Y-153346D02*
X614279Y-135263D01*
G01X627849Y-152763D02*
Y-135263D01*
X625229Y-138763D01*
G01Y-152763D02*
X630469D01*
G01X645349D02*
Y-135263D01*
X642729Y-138763D01*
G01Y-152763D02*
X647969D01*
G01X658919Y-153346D02*
X666779Y-135263D01*
G01X676201Y-138180D02*
X677511Y-136430D01*
X679039Y-135555D01*
X680786Y-135263D01*
X682969Y-135846D01*
X684497Y-137305D01*
X684934Y-139054D01*
X684716Y-140805D01*
X683842Y-142263D01*
X679476Y-145180D01*
X677511Y-147221D01*
X676201Y-150139D01*
X675764Y-152763D01*
X684934D01*
G01X697849Y-135263D02*
X696102Y-135846D01*
X694792Y-137305D01*
X693919Y-139054D01*
X693264Y-141388D01*
X693046Y-144013D01*
X693264Y-146638D01*
X693919Y-148972D01*
X694792Y-150722D01*
X696102Y-152180D01*
X697849Y-152763D01*
X699595Y-152180D01*
X700906Y-150722D01*
X701779Y-148972D01*
X702434Y-146638D01*
X702652Y-144013D01*
X702434Y-141388D01*
X701779Y-139054D01*
X700906Y-137305D01*
X699595Y-135846D01*
X697849Y-135263D01*
G01X715349Y-152763D02*
Y-135263D01*
X712729Y-138763D01*
G01Y-152763D02*
X717969D01*
G01X728046Y-150139D02*
X729355Y-151597D01*
X730884Y-152471D01*
X732849Y-152763D01*
X734814Y-152180D01*
X736342Y-151013D01*
X737434Y-148972D01*
X737652Y-146638D01*
X737216Y-144305D01*
X736124Y-142846D01*
X734595Y-141680D01*
X733067Y-141388D01*
X731539Y-141680D01*
X729574Y-142846D01*
X730229Y-135263D01*
X736124D01*
G01X623046Y-107763D02*
Y-90263D01*
X627412D01*
X629159Y-91138D01*
X630469Y-92305D01*
X631561Y-94054D01*
X632434Y-96097D01*
X632652Y-99013D01*
X632434Y-101930D01*
X631561Y-103972D01*
X630469Y-105722D01*
X629159Y-106888D01*
X627412Y-107763D01*
X623046D01*
G01X649279D02*
Y-96097D01*
G01Y-98138D02*
X648406Y-96972D01*
X647095Y-96388D01*
X645567Y-96097D01*
X644039Y-96680D01*
X642729Y-97846D01*
X641855Y-99596D01*
X641419Y-101930D01*
X641855Y-104263D01*
X642729Y-106013D01*
X644039Y-107180D01*
X645567Y-107763D01*
X647095Y-107471D01*
X648406Y-106597D01*
X649279Y-105430D01*
G01X662849Y-90263D02*
Y-107763D01*
G01X659792Y-96097D02*
X665906D01*
G01X677074Y-99888D02*
X684061D01*
X683406Y-97846D01*
X682314Y-96680D01*
X680786Y-96097D01*
X679257Y-96388D01*
X677947Y-97263D01*
X677074Y-99305D01*
X676637Y-101055D01*
Y-102805D01*
X677074Y-104555D01*
X678166Y-106305D01*
X679476Y-107471D01*
X681004Y-107763D01*
X682532Y-107180D01*
X684061Y-105430D01*
G54D13*
X15906Y48110D03*
Y58110D03*
Y68110D03*
Y78110D03*
Y88110D03*
Y481339D03*
Y491339D03*
Y501339D03*
Y511339D03*
Y521339D03*
Y741181D03*
Y751181D03*
Y761181D03*
Y771181D03*
Y781181D03*
Y1187323D03*
Y1197323D03*
Y1207323D03*
Y1217323D03*
Y1227323D03*
Y1447165D03*
Y1457165D03*
Y1467165D03*
Y1477165D03*
Y1487165D03*
Y1880394D03*
Y1890394D03*
Y1900394D03*
Y1910394D03*
Y1920394D03*
X138937Y1778819D03*
X128937D03*
X118937D03*
X165000Y1370500D03*
Y1390500D03*
Y1380500D03*
G54D23*
G01X32425Y177900D02*
Y206024D01*
X32763Y206362D01*
Y206363D01*
X34574Y208174D01*
Y222223D01*
X32597Y224200D01*
X30858D01*
X15700Y239358D01*
Y310754D01*
X8831Y317623D01*
Y446605D01*
X8829Y446607D01*
Y469968D01*
X8831Y469970D01*
Y659883D01*
X9855Y660907D01*
X9856D01*
X41224Y692275D01*
Y694774D01*
X43950Y697500D01*
X44500D01*
G01X43388Y694286D02*
Y691964D01*
X10581Y659157D01*
Y469245D01*
X10579Y469243D01*
Y447332D01*
X10581Y447330D01*
Y318419D01*
X17500Y311500D01*
Y240033D01*
X31533Y226000D01*
X33272D01*
X36324Y222948D01*
Y207424D01*
X34475Y205575D01*
Y180325D01*
X39300Y175500D01*
G01X41100Y231000D02*
X23900Y248200D01*
Y271000D01*
X21100Y273800D01*
Y321100D01*
X15946Y326254D01*
Y446915D01*
X14079Y448782D01*
Y467793D01*
X25181Y478895D01*
Y528319D01*
X21346Y532154D01*
Y558346D01*
X31500Y568500D01*
Y575500D01*
X50325Y594325D01*
Y702675D01*
X49500Y703500D01*
G01X46500Y705500D02*
Y702000D01*
X48575Y699925D01*
Y595575D01*
X29475Y576475D01*
Y568975D01*
X19596Y559096D01*
Y531404D01*
X23431Y527569D01*
Y479620D01*
X12329Y468518D01*
Y448057D01*
X14196Y446190D01*
Y325458D01*
X19300Y320354D01*
Y273054D01*
X22100Y270254D01*
Y245500D01*
X38000Y229600D01*
Y228500D01*
G01X31299Y358563D02*
X32475Y359739D01*
Y442525D01*
X21229Y453771D01*
Y463329D01*
X32800Y474900D01*
Y526100D01*
X45000Y538300D01*
Y576500D01*
X66500Y598000D01*
Y612500D01*
X71775Y617775D01*
Y663919D01*
X69500Y666194D01*
Y678049D01*
X64725Y682824D01*
Y843275D01*
X57809Y850191D01*
Y852500D01*
G01X18035Y572076D02*
X12331Y566372D01*
Y484914D01*
X15906Y481339D01*
G01X25148Y570800D02*
X15646Y561298D01*
Y529354D01*
X19481Y525519D01*
Y504914D01*
X15906Y501339D01*
G01X23450Y577491D02*
X18035Y572076D01*
G01X15906Y1447165D02*
X13896Y1445155D01*
Y1384604D01*
X30438Y1368062D01*
Y1367562D01*
G01X70500Y1161500D02*
Y1168948D01*
X69225Y1170223D01*
Y1176431D01*
X70775Y1177981D01*
Y1327225D01*
X30438Y1367562D01*
G01X15906Y1467165D02*
X19481Y1463590D01*
Y1438181D01*
X15646Y1434346D01*
Y1385554D01*
X73163Y1328037D01*
Y1158780D01*
G01X19200Y1707000D02*
X21425Y1704775D01*
Y1641125D01*
X17846Y1637546D01*
Y1495869D01*
X25181Y1488534D01*
Y1434281D01*
X21346Y1430446D01*
Y1389154D01*
X78988Y1331512D01*
Y1156288D01*
X76117Y1153417D01*
Y1143963D01*
X82500Y1137580D01*
Y1125500D01*
X125300Y1082700D01*
Y1006700D01*
X143000Y989000D01*
Y953032D01*
G01X19250Y1663100D02*
Y1641425D01*
X16096Y1638271D01*
Y1495144D01*
X23431Y1487809D01*
Y1435137D01*
X19596Y1431302D01*
Y1388404D01*
X77238Y1330762D01*
Y1157038D01*
X74367Y1154167D01*
Y1142633D01*
X80500Y1136500D01*
Y1125000D01*
X122900Y1082600D01*
Y1007400D01*
G01X137500Y682500D02*
X137875Y682875D01*
Y830375D01*
X154100Y846600D01*
X154200D01*
X154400Y846800D01*
Y846900D01*
X160300Y852800D01*
Y965100D01*
X157100Y968300D01*
Y983100D01*
X131749Y1008451D01*
Y1017300D01*
X130401Y1018648D01*
Y1073209D01*
X130400Y1073210D01*
Y1082600D01*
X86500Y1126500D01*
Y1143000D01*
X80900Y1148600D01*
Y1332100D01*
X36700Y1376300D01*
Y1410100D01*
X38496Y1411896D01*
Y1430300D01*
X27575Y1441221D01*
Y1488615D01*
X19596Y1496594D01*
Y1636095D01*
X23200Y1639699D01*
Y1762000D01*
X25000Y1763800D01*
G01X45300Y1776300D02*
X38300Y1769300D01*
X36500D01*
X24951Y1757751D01*
Y1637949D01*
X21346Y1634344D01*
Y1498254D01*
X29325Y1490275D01*
Y1442052D01*
X40246Y1431131D01*
Y1412754D01*
X42200Y1410800D01*
Y1374000D01*
X83500Y1332700D01*
Y1149500D01*
X88500Y1144500D01*
Y1127300D01*
X132150Y1083650D01*
Y1073935D01*
X132151Y1073934D01*
Y1019849D01*
X133900Y1018100D01*
Y1009000D01*
X159100Y983800D01*
Y970200D01*
X162050Y967250D01*
Y851975D01*
X154875Y844800D01*
X154870D01*
X140219Y830149D01*
Y685081D01*
X141800Y683500D01*
Y676300D01*
G01X78400Y86100D02*
X84500Y80000D01*
Y69253D01*
X88253Y65500D01*
G01X122500Y653650D02*
X76800Y607950D01*
Y594649D01*
X65451Y583300D01*
X62648D01*
X60900Y581552D01*
Y572900D01*
X50350Y562350D01*
Y536050D01*
X38250Y523950D01*
Y488426D01*
X38249Y488425D01*
Y486976D01*
X43146Y482079D01*
Y444598D01*
X38148Y439600D01*
Y433800D01*
X38149Y433799D01*
Y428772D01*
X38150Y428771D01*
Y363522D01*
X39950Y361722D01*
Y268751D01*
X54375Y254326D01*
Y231075D01*
X51925Y228625D01*
Y215875D01*
X56075Y211725D01*
Y206027D01*
X51525Y201477D01*
Y190523D01*
X57600Y184448D01*
Y184447D01*
X57601Y184446D01*
Y106799D01*
X78300Y86100D01*
X78400D01*
G01X81500Y75500D02*
Y78400D01*
X58749Y101151D01*
G01D02*
X55851Y104049D01*
Y183721D01*
X49775Y189797D01*
Y205175D01*
X51575Y206975D01*
Y211677D01*
X49825Y213427D01*
Y237077D01*
X50375Y237627D01*
Y255825D01*
X38200Y268000D01*
Y360997D01*
X36400Y362797D01*
Y362799D01*
X36399Y362800D01*
Y433074D01*
X36398Y433075D01*
Y440325D01*
X36399Y440326D01*
Y440399D01*
X41396Y445396D01*
Y481353D01*
X36498Y486251D01*
Y487701D01*
X36499Y487702D01*
Y489150D01*
X36500Y489151D01*
Y524800D01*
X48600Y536900D01*
Y563100D01*
X59100Y573600D01*
Y582227D01*
X61973Y585100D01*
X64776D01*
X75000Y595324D01*
Y609624D01*
X117400Y652024D01*
Y653100D01*
G01X149606Y204409D02*
X143709D01*
X115300Y176000D01*
X89693D01*
X84400Y170707D01*
Y170453D01*
X82211Y168264D01*
X81957D01*
X75300Y161607D01*
Y155300D01*
G01X49924Y153261D02*
Y166376D01*
X47800Y168500D01*
Y183800D01*
X43375Y188225D01*
Y203875D01*
X47395Y207895D01*
Y240000D01*
X38800Y248595D01*
Y264900D01*
X36400Y267300D01*
Y360000D01*
X34649Y361751D01*
Y432349D01*
X34648Y432350D01*
Y441050D01*
X34649Y441051D01*
Y441849D01*
X39646Y446846D01*
Y480628D01*
X34748Y485526D01*
Y488426D01*
X34749Y488427D01*
Y489876D01*
X34750Y489877D01*
Y525550D01*
X46850Y537650D01*
Y575150D01*
X68400Y596700D01*
Y611900D01*
X100600Y644100D01*
Y656600D01*
G01X53400Y191300D02*
X54175Y192075D01*
X72825D01*
X78386Y186514D01*
X83014D01*
X84764Y188264D01*
X114264D01*
X143300Y217300D01*
Y225700D01*
X147300Y229700D01*
X162130D01*
X163800Y231370D01*
Y257200D01*
X168904Y262304D01*
X180904D01*
X192300Y273700D01*
Y388600D01*
X189800Y391100D01*
Y421500D01*
X194400Y426100D01*
Y439900D01*
X185200Y449100D01*
Y449200D01*
X182300Y452100D01*
Y531000D01*
X169000Y544300D01*
X168999D01*
X149500Y563799D01*
Y586800D01*
X177975Y615275D01*
Y619625D01*
X169800Y627800D01*
Y682500D01*
X161500Y690800D01*
Y691700D01*
G01X41100Y231000D02*
Y207200D01*
X39425Y205525D01*
Y185475D01*
X43700Y181200D01*
G01X43400Y174325D02*
X43175D01*
X36245Y181255D01*
Y204845D01*
X38400Y207000D01*
Y228100D01*
X38000Y228500D01*
G01X52700Y162300D02*
Y166200D01*
X49600Y169300D01*
Y184500D01*
X45125Y188975D01*
Y203125D01*
X49700Y207700D01*
Y209700D01*
G01X169606Y224409D02*
X169605D01*
X164600Y219404D01*
Y212900D01*
X162484Y210784D01*
X145000D01*
X112216Y178000D01*
X84500D01*
X83014Y176514D01*
X78482D01*
X71596Y183400D01*
X64400D01*
G01X47800Y199200D02*
X48000Y199000D01*
Y188600D01*
X52500Y184100D01*
Y175200D01*
G01X64000Y199700D02*
X67771D01*
X79207Y188264D01*
X82211D01*
X84400Y190453D01*
Y190707D01*
X90093Y196400D01*
X100302D01*
X107000Y203098D01*
Y210700D01*
X110709Y214409D01*
G01X192007Y482593D02*
X198500Y476100D01*
Y444800D01*
X196575Y442875D01*
Y422675D01*
X194775Y420875D01*
Y272075D01*
X183254Y260554D01*
X178103D01*
X175980Y258431D01*
Y257180D01*
X165800Y247000D01*
Y224500D01*
X160334Y219034D01*
X149034D01*
X116500Y186500D01*
X90193D01*
X84400Y180707D01*
Y180453D01*
X82211Y178264D01*
X79207D01*
X70500Y186971D01*
Y190200D01*
G01X90709Y234409D02*
X85334Y239784D01*
X74416D01*
X65874Y248326D01*
Y254751D01*
X50074Y270551D01*
Y282400D01*
X46950Y285524D01*
Y364624D01*
X46175Y365399D01*
X46174D01*
X45150Y366423D01*
Y431672D01*
X45149Y431673D01*
Y436700D01*
X50200Y441751D01*
Y482050D01*
X59100Y490950D01*
Y560424D01*
X71975Y573299D01*
Y574623D01*
X80300Y582948D01*
Y587700D01*
X84100Y591500D01*
Y605173D01*
X129625Y650698D01*
Y657375D01*
X121500Y665500D01*
Y683500D01*
G01X119576Y687008D02*
X116825Y684257D01*
Y667675D01*
X127875Y656625D01*
Y651423D01*
X82200Y605748D01*
Y592100D01*
X66400Y576300D01*
Y570400D01*
X57350Y561350D01*
Y491675D01*
X48450Y482775D01*
Y442477D01*
X43398Y437425D01*
Y435975D01*
X43399Y435974D01*
Y430948D01*
X43400Y430947D01*
Y365698D01*
X45200Y363898D01*
Y283824D01*
X48324Y280700D01*
Y265676D01*
X56900Y257100D01*
Y253247D01*
X67475Y242672D01*
Y216473D01*
X79539Y204409D01*
X80709D01*
G01X120702Y690847D02*
X123675Y687874D01*
Y665825D01*
X131375Y658125D01*
Y649973D01*
X86705Y605303D01*
Y593995D01*
X88875Y591825D01*
Y590223D01*
X82100Y583448D01*
Y575800D01*
X60850Y554550D01*
Y490225D01*
X51950Y481325D01*
Y441026D01*
X46899Y435975D01*
Y434525D01*
X46900Y434524D01*
Y367149D01*
X47924Y366125D01*
X47925D01*
X48700Y365350D01*
Y287225D01*
X51825Y284100D01*
Y271275D01*
X67625Y255475D01*
Y249974D01*
X69574Y248025D01*
X79198D01*
X79207Y248034D01*
X82211D01*
X84334Y245911D01*
Y245657D01*
X90191Y239800D01*
X139300D01*
X140900Y238200D01*
X155815D01*
X159606Y234409D01*
G01X71400Y208150D02*
X78766Y200784D01*
X82211D01*
X87000Y205573D01*
Y215827D01*
X90073Y218900D01*
X92802D01*
X96200Y222298D01*
Y225027D01*
X99207Y228034D01*
X107084D01*
X110709Y224409D01*
G01X69900Y236600D02*
X70500Y236000D01*
X73252D01*
X77900Y231352D01*
Y229034D01*
G01X117600Y234900D02*
X114466Y238034D01*
X99207D01*
X97000Y235827D01*
Y235573D01*
X91627Y230200D01*
X91373D01*
X86200Y225027D01*
Y222298D01*
X82002Y218100D01*
X71100D01*
X70600Y217600D01*
G01X74800Y231800D02*
Y231500D01*
X69400Y226100D01*
G01X61300Y229400D02*
Y215598D01*
X77864Y199034D01*
X83034D01*
X84784Y200784D01*
X97084D01*
X100709Y204409D01*
G01X122100Y230100D02*
X122000Y230000D01*
X98698D01*
X94400Y225702D01*
Y222973D01*
X92127Y220700D01*
X89398D01*
X84400Y215702D01*
Y212973D01*
X82211Y210784D01*
X75816D01*
X75300Y211300D01*
G01X85676Y231100D02*
X84400Y229824D01*
Y222973D01*
X82211Y220784D01*
X73016D01*
X72100Y221700D01*
G01X53500Y199700D02*
X55375Y201575D01*
X68371D01*
X72646Y197300D01*
X77600D01*
X77616Y197284D01*
X83784D01*
X84700Y198200D01*
X99627D01*
X104334Y202907D01*
Y220784D01*
X100709Y224409D01*
G01X60300Y275700D02*
Y288300D01*
X54550Y294050D01*
Y367775D01*
X52750Y369575D01*
Y433550D01*
X59104Y439904D01*
Y441094D01*
G01X57500Y268500D02*
X57650Y268650D01*
Y288050D01*
X52500Y293200D01*
Y366925D01*
X50700Y368725D01*
Y434400D01*
X55750Y439450D01*
Y479750D01*
X64650Y488650D01*
Y539950D01*
X76166Y551466D01*
G01X128600Y669500D02*
Y663400D01*
X133125Y658875D01*
Y649248D01*
X88455Y604578D01*
Y598197D01*
X90875Y595777D01*
Y581075D01*
X87000Y577200D01*
Y566800D01*
X62600Y542400D01*
Y489500D01*
X53700Y480600D01*
Y440300D01*
X48650Y435250D01*
Y367875D01*
X50450Y366075D01*
Y290250D01*
X54800Y285900D01*
Y276400D01*
X54000Y275600D01*
G01X45800Y277800D02*
X43450Y280150D01*
Y363173D01*
X41650Y364973D01*
Y430221D01*
X41649Y430222D01*
Y435249D01*
X41648Y435250D01*
Y438150D01*
X46700Y443202D01*
Y483500D01*
X55600Y492400D01*
Y562100D01*
X64600Y571100D01*
Y577400D01*
X80400Y593200D01*
Y606423D01*
X126125Y652148D01*
Y655375D01*
X118127Y663373D01*
Y663400D01*
G01X114000Y663350D02*
X116599Y660751D01*
X118051D01*
X124375Y654427D01*
Y652873D01*
X78600Y607098D01*
Y593900D01*
X62800Y578100D01*
Y571800D01*
X53000Y562000D01*
Y536181D01*
X40000Y523181D01*
Y487700D01*
X44950Y482750D01*
Y443927D01*
X39898Y438875D01*
Y434525D01*
X39899Y434524D01*
Y429497D01*
X39900Y429496D01*
Y364247D01*
X40924Y363223D01*
X40925D01*
X41700Y362448D01*
Y274000D01*
X43400Y272300D01*
G01X59104Y441094D02*
X57800Y442398D01*
Y478900D01*
X66800Y487900D01*
Y537700D01*
X128550Y599450D01*
X144026D01*
X158724Y614148D01*
Y625313D01*
X153350Y630687D01*
Y659823D01*
X151432Y661741D01*
G01X148995Y658568D02*
X151300Y656263D01*
Y629837D01*
X156674Y624463D01*
Y617902D01*
X144947Y606175D01*
X132375D01*
X127800Y601600D01*
X127700D01*
X118400Y592300D01*
Y592200D01*
X90800Y564600D01*
X89300D01*
X76166Y551466D01*
G01X82900Y620600D02*
X82400D01*
X73200Y611400D01*
Y596600D01*
X72500Y595900D01*
G01X56800Y576950D02*
Y582600D01*
X70300Y596100D01*
Y611200D01*
X106400Y647300D01*
Y648300D01*
G01X112800Y653500D02*
Y650600D01*
X82900Y620700D01*
Y620600D01*
G01X67302Y1133490D02*
X72675Y1128117D01*
Y825875D01*
X70525Y823725D01*
Y764225D01*
X80369Y754381D01*
Y697058D01*
X79271Y695960D01*
X76383D01*
X72475Y692052D01*
Y684998D01*
X79000Y678473D01*
Y675500D01*
G01X80900Y668400D02*
Y673600D01*
X79000Y675500D01*
G01X86443Y662853D02*
X86296Y663000D01*
X80749D01*
X76950Y666799D01*
Y669950D01*
X73500Y673400D01*
Y679000D01*
X68975Y683525D01*
Y693503D01*
X75375Y699903D01*
Y753475D01*
X67025Y761825D01*
Y826325D01*
X69175Y828475D01*
Y901225D01*
X63800Y906600D01*
Y917100D01*
X54200Y926700D01*
G01X73000Y728000D02*
Y727400D01*
X66925Y721325D01*
Y683100D01*
X71250Y678775D01*
Y669172D01*
X80673Y659749D01*
X83900D01*
G01X88967D02*
X83900D01*
G01X84504Y666353D02*
X84376Y666225D01*
X79999D01*
X78725Y667499D01*
Y670775D01*
X75250Y674250D01*
Y679748D01*
X70725Y684273D01*
Y692778D01*
X77125Y699178D01*
Y754275D01*
X68775Y762625D01*
Y824575D01*
X70925Y826725D01*
Y903375D01*
X67000Y907300D01*
G01X84000Y674000D02*
X81950Y676050D01*
Y677998D01*
X74225Y685723D01*
Y691150D01*
X75571Y692496D01*
G01X84000Y674000D02*
Y672400D01*
X90674Y665726D01*
Y663367D01*
G01X72400Y822900D02*
Y766025D01*
X82925Y755500D01*
Y691967D01*
X86597Y688295D01*
Y681103D01*
G01X60900Y670200D02*
X60500Y670600D01*
Y674700D01*
G01D02*
Y682540D01*
G01X76100Y686900D02*
X77500D01*
X80479Y683921D01*
G01D02*
X83850Y680550D01*
Y678109D01*
G01X56000Y885500D02*
Y882448D01*
X57809Y880639D01*
Y852500D01*
G01X67000Y907300D02*
Y1013152D01*
X54652Y1025500D01*
X53500D01*
G01X54000Y996500D02*
X53000Y995500D01*
Y927900D01*
X54200Y926700D01*
G01X37700Y991600D02*
X37500Y991800D01*
Y998000D01*
G01D02*
Y1099823D01*
G01X78292Y1148041D02*
X84500Y1141833D01*
Y1126000D01*
X128650Y1081850D01*
Y1072485D01*
X128651Y1072484D01*
Y1017449D01*
X129500Y1016600D01*
Y1008100D01*
X153125Y984475D01*
Y963875D01*
X156500Y960500D01*
Y947077D01*
X151325Y941902D01*
Y846325D01*
X135325Y830325D01*
Y681568D01*
X132110Y678353D01*
G01X147900Y588100D02*
X147600Y587800D01*
Y557100D01*
X151200Y553500D01*
Y452000D01*
X137000Y437800D01*
Y427600D01*
X141400Y423200D01*
Y383600D01*
X135800Y378000D01*
Y246200D01*
X131400Y241800D01*
X120000D01*
X112700Y249100D01*
X105400D01*
X102700Y246400D01*
Y246300D01*
X102600D01*
X100709Y244409D01*
G01X115300Y551800D02*
X116624D01*
X146175Y522249D01*
Y454099D01*
X136901Y444825D01*
X135824D01*
X127200Y436201D01*
Y246000D01*
G01X90630Y602020D02*
X97625Y595025D01*
X116975D01*
X140753Y618803D01*
X152700D01*
G01X136500Y597000D02*
X129000D01*
G01X170349Y619949D02*
Y616449D01*
X154550Y600650D01*
X148250D01*
X144600Y597000D01*
X136500D01*
G01X122692Y1257808D02*
X126500Y1254000D01*
Y1095500D01*
X135651Y1086349D01*
Y1080358D01*
X135650Y1080357D01*
Y1075385D01*
X135651Y1075384D01*
Y1021749D01*
X137500Y1019900D01*
Y1011000D01*
X160800Y987700D01*
X163600D01*
X165800Y985500D01*
Y850750D01*
X156250Y841200D01*
X156220D01*
X143719Y828699D01*
Y687306D01*
X145725Y685300D01*
Y671225D01*
X140773Y666273D01*
Y664627D01*
X142825Y662575D01*
Y623725D01*
X116000Y596900D01*
G01X124000Y1247600D02*
Y1094500D01*
X133901Y1084599D01*
Y1081083D01*
X133900Y1081082D01*
Y1074660D01*
X133901Y1074659D01*
Y1020954D01*
X135655Y1019200D01*
Y1009845D01*
X160900Y984600D01*
Y971600D01*
X163900Y968600D01*
Y851325D01*
X155575Y843000D01*
X155545D01*
X141969Y829424D01*
Y686131D01*
X143975Y684125D01*
Y672351D01*
X139023Y667399D01*
Y663877D01*
X141075Y661825D01*
Y626783D01*
X113655Y599363D01*
G01X131135Y639554D02*
X134875Y643294D01*
Y659625D01*
X130894Y663606D01*
Y677094D01*
X132110Y678310D01*
Y678353D01*
G01X108200Y655825D02*
Y650000D01*
X106500Y648300D01*
X106400D01*
G01X138900Y650100D02*
X137300Y651700D01*
Y659700D01*
X132725Y664275D01*
Y669725D01*
X137500Y674500D01*
Y682500D01*
G01X100600Y656600D02*
X102500Y658500D01*
Y668700D01*
X100600Y670600D01*
G01X128600Y669500D02*
Y677920D01*
X133575Y682895D01*
Y831075D01*
X149375Y846875D01*
Y942427D01*
X154750Y947802D01*
Y956425D01*
X150500Y960675D01*
Y976500D01*
G01X100200Y663900D02*
X99849D01*
X92849Y670900D01*
Y674851D01*
X86597Y681103D01*
G01X115217Y765517D02*
X111625Y761925D01*
Y700675D01*
X113200Y699100D01*
Y668327D01*
X118127Y663400D01*
G01X111100Y788200D02*
Y783200D01*
X107875Y779975D01*
Y737100D01*
X107873Y737098D01*
Y709779D01*
X107875Y709777D01*
Y708223D01*
X107873Y708221D01*
Y697976D01*
X106323Y696426D01*
Y679177D01*
X109288Y676212D01*
Y673099D01*
X109287Y673098D01*
Y666172D01*
X109005Y665890D01*
G01X116402Y779402D02*
X109875Y772875D01*
Y699925D01*
X111400Y698400D01*
Y665950D01*
X114000Y663350D01*
G01X107164Y862285D02*
X108954Y864075D01*
X114177D01*
X126675Y851577D01*
Y776975D01*
X115217Y765517D01*
G01X106404Y840700D02*
X108154D01*
X116875Y831979D01*
Y822575D01*
X111100Y816800D01*
Y788200D01*
G01X111500Y851600D02*
Y843200D01*
X118625Y836075D01*
Y781625D01*
X116402Y779402D01*
G01X98900Y822900D02*
Y835000D01*
X98425Y835475D01*
Y871125D01*
X101500Y874200D01*
G01X100300Y841000D02*
X106104D01*
X106404Y840700D01*
G01X111500Y851600D02*
Y860300D01*
X113400Y862200D01*
G01X107164Y862285D02*
X103453D01*
X102300Y863438D01*
G01X146500Y953030D02*
X144627Y951157D01*
X142223D01*
X141125Y952255D01*
Y987335D01*
X122900Y1005560D01*
Y1007400D01*
G01X149772Y954121D02*
Y954380D01*
X147000Y957152D01*
Y987700D01*
X127500Y1007200D01*
Y1014900D01*
X127200Y1015200D01*
G01X128700Y1408000D02*
Y1095800D01*
X137401Y1087099D01*
Y1079633D01*
X137400Y1079632D01*
Y1076110D01*
X137401Y1076109D01*
Y1022649D01*
X139250Y1020800D01*
Y1012050D01*
X161100Y990200D01*
X165173D01*
X167550Y987823D01*
Y849975D01*
X148650Y831075D01*
Y734250D01*
X148879Y734021D01*
Y698879D01*
X148825Y698825D01*
Y689975D01*
X150975Y687825D01*
Y687778D01*
X150978Y687775D01*
G01X135601Y1416200D02*
Y1099099D01*
X143701Y1090999D01*
Y1078721D01*
X143703Y1078719D01*
Y1026401D01*
X143725Y1026379D01*
Y1026378D01*
X143727Y1026376D01*
Y1025950D01*
X146075Y1023602D01*
Y1023600D01*
X146700Y1022975D01*
Y1019000D01*
X146800Y1018900D01*
G01X134500Y1420000D02*
X133551Y1419051D01*
Y1097549D01*
X141651Y1089449D01*
Y1077871D01*
X141653Y1077869D01*
Y1025551D01*
X141675Y1025529D01*
Y1025528D01*
X141677Y1025526D01*
Y1025100D01*
X143900Y1022877D01*
Y1022700D01*
G01X119500Y1261000D02*
X122692Y1257808D01*
G01X119000Y1255968D02*
X124000Y1250968D01*
Y1247600D01*
G01X109500Y1438000D02*
X103500Y1432000D01*
X102600D01*
X101600Y1431000D01*
G01X98500Y1428400D02*
X99000D01*
X101600Y1431000D01*
G01X169606Y244409D02*
Y244410D01*
X174096Y248900D01*
X179825D01*
X196525Y265600D01*
Y420125D01*
X198325Y421925D01*
Y438402D01*
X200500Y440577D01*
Y477900D01*
X189825Y488575D01*
Y520673D01*
X186950Y523548D01*
Y533550D01*
X184003Y536497D01*
G01X169606Y234409D02*
Y234410D01*
X174696Y239500D01*
X182200D01*
X198276Y255576D01*
Y408353D01*
X203175Y413252D01*
Y481901D01*
X196325Y488751D01*
Y528551D01*
X182588Y542288D01*
G01X142500Y1420500D02*
Y1101000D01*
X149000Y1094500D01*
Y1029500D01*
X180000Y998500D01*
Y988400D01*
X184175Y984225D01*
Y949575D01*
X182325Y947725D01*
Y775901D01*
X168125Y761701D01*
Y730401D01*
X172300Y726226D01*
Y697600D01*
X181100Y688800D01*
Y644400D01*
X183800Y641700D01*
Y618300D01*
X151325Y585825D01*
Y564600D01*
X184325Y531600D01*
Y490275D01*
X192007Y482593D01*
G01X160000Y562500D02*
Y560500D01*
X184003Y536497D01*
G01X139200Y653900D02*
Y661200D01*
X136973Y663427D01*
Y671473D01*
X141800Y676300D01*
G01X142648Y665429D02*
X146000Y662077D01*
Y641400D01*
G01X152700Y618803D02*
Y621500D01*
X146000Y628200D01*
Y641400D01*
G01X150978Y687775D02*
X151000Y687753D01*
Y673781D01*
X142648Y665429D01*
G01X146800Y1018900D02*
Y1017600D01*
X173900Y990500D01*
Y847300D01*
X155000Y828400D01*
Y736900D01*
X159700Y732200D01*
Y692700D01*
X159450Y692450D01*
Y682950D01*
X159525Y682875D01*
Y675362D01*
X151432Y667269D01*
Y661741D01*
G01X148995Y658568D02*
Y667732D01*
X157475Y676212D01*
Y682025D01*
X157400Y682100D01*
Y693400D01*
X157567Y693567D01*
Y729267D01*
X157600Y729300D01*
Y731300D01*
X153200Y735700D01*
Y735800D01*
X152900Y736100D01*
Y829300D01*
X158700Y835100D01*
X158800D01*
X165900Y842200D01*
Y842300D01*
X171800Y848200D01*
Y989700D01*
X166600Y994900D01*
X166500D01*
X144700Y1016700D01*
Y1016800D01*
X143900Y1017600D01*
Y1022700D01*
G01X150700Y691700D02*
Y694200D01*
X152000Y695500D01*
Y695688D01*
G01X153192Y705890D02*
Y696880D01*
X152000Y695688D01*
G01X155000Y974500D02*
Y966900D01*
X158500Y963400D01*
Y898700D01*
X157800Y898000D01*
G01X147500Y900500D02*
X147625Y900625D01*
Y945125D01*
X153000Y950500D01*
Y952200D01*
X152747Y952453D01*
Y952474D01*
G54D14*
X27559Y157480D03*
Y629921D03*
X17716Y1338583D03*
X27559Y1811023D03*
X179134Y78740D03*
X179133Y570866D03*
X179134Y1161417D03*
Y1889764D03*
G54D15*
X32425Y177900D03*
X26450Y274750D03*
X34200Y284800D03*
X32600Y290500D03*
X25500Y321200D03*
X21600Y333800D03*
X29500Y343500D03*
X23100Y342400D03*
X32675Y299500D03*
X23400Y353500D03*
X34000Y448000D03*
X29500Y410500D03*
X33200Y468900D03*
X14000Y476000D03*
X28800Y533700D03*
X5304Y548800D03*
Y528900D03*
X33450Y574300D03*
X5094Y574500D03*
X29500Y586500D03*
X23450Y577491D03*
X25148Y570800D03*
X27000Y573800D03*
X4594Y749000D03*
Y714000D03*
X5000Y1355000D03*
X26700Y1529800D03*
X28000Y1596800D03*
X13300Y1644300D03*
X10500Y1648800D03*
X35500Y1670500D03*
X31400Y1648200D03*
X13300Y1689600D03*
X19542Y1710518D03*
X29100Y1721550D03*
X34000Y1691500D03*
X19200Y1707000D03*
X25000Y1763800D03*
X22000Y1787800D03*
X27400Y1899400D03*
X64000Y67553D03*
X64500Y53000D03*
X70454Y60031D03*
X74000Y60500D03*
X79000Y65500D03*
X75000Y67500D03*
X84500Y56500D03*
X81500Y75500D03*
X63500Y63500D03*
X59600Y125800D03*
X75300Y155300D03*
X49924Y153261D03*
X53000Y171500D03*
X65000Y166300D03*
X60350Y151950D03*
X39300Y181100D03*
X63500Y179300D03*
X53400Y191300D03*
X39300Y175500D03*
X43700Y181200D03*
X43400Y174325D03*
X52700Y162300D03*
X64400Y183400D03*
X52500Y175200D03*
X70500Y190200D03*
X54400Y217000D03*
X65200Y207850D03*
X57424Y232974D03*
X42720Y233990D03*
X65000Y241500D03*
Y235400D03*
X54200Y207850D03*
Y220700D03*
X51700Y234800D03*
X41100Y231000D03*
X71400Y208150D03*
X69900Y236600D03*
X77900Y229034D03*
X70600Y217600D03*
X74800Y231800D03*
X69400Y226100D03*
X61300Y229400D03*
X38000Y228500D03*
X75300Y211300D03*
X85676Y231100D03*
X72100Y221700D03*
X49700Y209700D03*
X53500Y199700D03*
X47800Y199200D03*
X64000Y199700D03*
X60300Y275700D03*
X57500Y268500D03*
X68000Y268000D03*
X70600Y250500D03*
X42500Y254100D03*
X48500Y248600D03*
X42500Y260200D03*
X36000Y260386D03*
X58936Y256289D03*
X52500Y248500D03*
X50800Y266400D03*
X54000Y275600D03*
X45800Y277800D03*
X43400Y272300D03*
X78000Y429500D03*
X52100Y513100D03*
X46500Y511000D03*
X46000Y516000D03*
X51000Y529500D03*
X66000Y550500D03*
X71445Y532192D03*
X72397Y528297D03*
X77800Y540300D03*
X63400Y581400D03*
X49700Y568900D03*
X65000Y561500D03*
X78400Y583700D03*
X70350Y558850D03*
X54600Y573400D03*
X82000Y652000D03*
X66200Y653500D03*
X84200Y643865D03*
X75571Y692496D03*
X53000Y673500D03*
X57684Y697639D03*
X64000Y666600D03*
X52500Y682500D03*
X78494Y697835D03*
X53000Y695100D03*
X39800Y681400D03*
X86597Y681103D03*
X43388Y694286D03*
X49500Y703500D03*
X46500Y705500D03*
X44500Y697500D03*
X60900Y670200D03*
X60500Y682540D03*
X76100Y686900D03*
X83850Y678109D03*
X73000Y728000D03*
X69000Y726800D03*
X71500Y735500D03*
X73500Y732000D03*
X86500Y723500D03*
X57500Y844500D03*
X72400Y822900D03*
X51200Y827000D03*
X61207Y828350D03*
X49600Y889400D03*
X55700Y880000D03*
X59500Y881600D03*
X57500Y890300D03*
X56000Y885500D03*
X64600Y882700D03*
X61600Y885200D03*
X67200Y888800D03*
X54300Y915500D03*
X54000Y996500D03*
X70800Y990500D03*
X57500Y987800D03*
Y984300D03*
X83500Y976300D03*
Y972800D03*
X83000Y979800D03*
X53800Y1006200D03*
X53500Y1025500D03*
X56000Y1021500D03*
X54500Y1035500D03*
X51000Y1018000D03*
X82094Y1112500D03*
X64500Y1099000D03*
X37500Y1099823D03*
X70500Y1161500D03*
X73163Y1158780D03*
X71100Y1171000D03*
X68800Y1178800D03*
X39400Y1381300D03*
X44500Y1380500D03*
X45500Y1400000D03*
X80000Y1472000D03*
X83200Y1455500D03*
X45000Y1428000D03*
X36400Y1523400D03*
X67700Y1568700D03*
X43500Y1620700D03*
X42700Y1606000D03*
X38400Y1596700D03*
X83000Y1619703D03*
X83050Y1616000D03*
X42500Y1673000D03*
X44500Y1678000D03*
X43600Y1668300D03*
X43300Y1646600D03*
X45500Y1690000D03*
X41500Y1692000D03*
X40300Y1703900D03*
X44100Y1685200D03*
X45300Y1776300D03*
X52500Y1756000D03*
X55900Y1881500D03*
X62000Y1877000D03*
X57900Y1899800D03*
X65300Y1886600D03*
X38700Y1893800D03*
X41500Y1889500D03*
X60300Y1892300D03*
X47000Y1886200D03*
X79900Y1923000D03*
X109500Y62000D03*
X89500Y49500D03*
X99500Y61000D03*
X115000Y76500D03*
X109000D03*
X98500Y73000D03*
X115500Y59500D03*
X97000Y51500D03*
X91500Y88500D03*
Y92500D03*
X92500Y73000D03*
X88253Y65500D03*
X112000Y101000D03*
X104500D03*
X91000Y97000D03*
X93000Y107000D03*
X93900Y111800D03*
X93500Y101500D03*
X117600Y234900D03*
X122100Y230100D03*
X127200Y246000D03*
X122500Y441000D03*
X135500D03*
X108100Y477650D03*
X91300Y528200D03*
X108900Y541300D03*
X102700Y541000D03*
X106300Y553200D03*
X110400Y550800D03*
X87700Y528000D03*
X132500Y539621D03*
X115300Y551800D03*
X129000Y597000D03*
X124200Y568400D03*
X119800Y568300D03*
X133500Y575500D03*
X137000Y589900D03*
X133500Y582000D03*
X134600Y586700D03*
X88000Y586500D03*
X101000Y583000D03*
X96000Y588000D03*
X89000Y595000D03*
X87000Y591000D03*
X135000Y561500D03*
X121000Y581500D03*
X124900Y582000D03*
X91300Y577000D03*
X92200Y553800D03*
X116000Y596900D03*
X113655Y599363D03*
X128900Y580500D03*
X122300Y575000D03*
X131135Y639554D03*
X87000Y648000D03*
X122500Y653650D03*
X117400Y653100D03*
X91250Y704700D03*
X134600Y665600D03*
X130000Y700500D03*
X122500D03*
X114500D03*
X105500Y702500D03*
X93000Y698500D03*
X88500Y700000D03*
X98000Y698500D03*
Y703000D03*
X100200Y663900D03*
X118127Y663400D03*
X109005Y665890D03*
X114000Y663350D03*
X130000Y753000D03*
Y746000D03*
X119500Y757500D03*
Y746500D03*
Y739500D03*
X113500Y729000D03*
Y736000D03*
Y747000D03*
Y756000D03*
Y721000D03*
X106000Y709000D03*
X98000Y708000D03*
X130000Y764000D03*
X118700Y840700D03*
X98900Y822900D03*
X114900Y824100D03*
X106404Y840700D03*
X100300Y841000D03*
X111500Y851600D03*
X101500Y874200D03*
X102300Y863438D03*
X107164Y862285D03*
X113400Y862200D03*
X125400Y983600D03*
Y992000D03*
X97300Y990800D03*
X94000Y971800D03*
X104000Y1062500D03*
Y1049500D03*
X127200Y1015200D03*
X105000Y1181000D03*
X119500Y1261000D03*
X119000Y1255968D03*
X128700Y1408000D03*
X135601Y1416200D03*
X134500Y1420000D03*
X125000Y1398500D03*
X100860Y1402260D03*
X111000Y1394000D03*
X125100Y1402500D03*
X131174Y1412700D03*
X89000Y1428171D03*
X110000Y1429500D03*
X132000Y1436500D03*
X112750Y1491250D03*
X121000Y1506500D03*
X113000D03*
X117000D03*
X109000D03*
X133000Y1505500D03*
X128999Y1506499D03*
X125000Y1506500D03*
X135008Y1508245D03*
X132300Y1491100D03*
X108500Y1569000D03*
X113200Y1622800D03*
Y1619300D03*
X91100Y1922800D03*
X128900Y1923300D03*
X104600Y1923400D03*
X133500Y1906500D03*
X149500Y52000D03*
X146960Y432400D03*
X142000Y478500D03*
X165300Y481100D03*
X144000Y509500D03*
X166100Y527900D03*
X147000Y529900D03*
X156300Y552100D03*
X142500Y550000D03*
X162500Y527900D03*
X159850Y541800D03*
X182588Y542288D03*
X154600Y581500D03*
X159250Y590250D03*
X145800Y594400D03*
X142100Y581400D03*
X160000Y562500D03*
X147900Y588100D03*
X138900Y650100D03*
X139200Y653900D03*
X174196Y628196D03*
X150978Y687775D03*
X142648Y665429D03*
X165433Y692372D03*
X161000Y674000D03*
X157500Y664500D03*
X147000Y703000D03*
X149000Y677000D03*
X155200Y679500D03*
X161500Y691700D03*
X150700D03*
X153192Y705890D03*
X146000Y755000D03*
X166000Y751500D03*
X170000Y745500D03*
X161600Y739800D03*
X161500Y747500D03*
X146000Y726000D03*
X165900Y717300D03*
X146000Y738000D03*
X175100Y710000D03*
X158600Y752600D03*
X146000Y765500D03*
Y796500D03*
Y782500D03*
X166000Y760000D03*
X166500Y775500D03*
X161500Y759000D03*
Y768000D03*
Y778000D03*
X146500Y812000D03*
X146000Y824000D03*
X180000Y856000D03*
X162000Y817500D03*
X174000Y834500D03*
X168000Y830000D03*
X180000Y872500D03*
X179500Y884000D03*
X179900Y900900D03*
X157800Y898000D03*
X147500Y900500D03*
X180000Y960400D03*
X179900Y925700D03*
X179800Y941400D03*
X180000Y912500D03*
X143000Y953032D03*
X146500Y953030D03*
X149772Y954121D03*
X152747Y952474D03*
X163100Y978600D03*
X163200Y985200D03*
X149800Y1008700D03*
X179000Y1005000D03*
X180500Y973200D03*
X150500Y976500D03*
X155000Y974500D03*
X155500Y1030000D03*
X153500Y1033500D03*
X151500Y1030500D03*
X159500Y1062000D03*
X163000Y1042500D03*
X146500Y1397100D03*
X155900D03*
X139900Y1415100D03*
X142500Y1420500D03*
X169000Y1426750D03*
X158500Y1466500D03*
X151500Y1438500D03*
X157500Y1454800D03*
X142000Y1494800D03*
X147500Y1498000D03*
X153500Y1496500D03*
X143518Y1567520D03*
X177500Y1569500D03*
X141300Y1625000D03*
X169876Y1626303D03*
X141500Y1621600D03*
X173270Y1626517D03*
X152500Y1883100D03*
X184500Y1920500D03*
X170000D03*
X162100Y1912000D03*
X151900Y1891400D03*
X146300Y1913700D03*
X142400Y1923800D03*
X176700Y1923900D03*
X177700Y1912800D03*
X157900Y1923100D03*
X201500Y165000D03*
X191400Y432405D03*
X202210Y638500D03*
X201500Y691500D03*
X202500Y666000D03*
X201500Y726500D03*
X202500Y755500D03*
X201500Y777000D03*
X201389Y797000D03*
X202000Y859500D03*
X202500Y822000D03*
Y846500D03*
X202000Y890000D03*
X202210Y903500D03*
X202000Y875000D03*
X202500Y945500D03*
X202000Y918000D03*
X202500Y962000D03*
X201500Y931500D03*
X202500Y1006000D03*
Y977500D03*
X201500Y991000D03*
X202000Y1037000D03*
Y1052000D03*
X201500Y1019000D03*
X201389Y1067000D03*
X201500Y1082500D03*
X195000Y1112000D03*
X201500Y1147000D03*
X202000Y1212000D03*
X202500Y1179000D03*
X202000Y1246000D03*
X201500Y1306500D03*
X202500Y1280000D03*
X201500Y1359500D03*
Y1350000D03*
X201700Y1388300D03*
X201500Y1413000D03*
X202400Y1444000D03*
X201389Y1425500D03*
X202210Y1462000D03*
X194500Y1510000D03*
Y1505500D03*
X196500Y1572000D03*
Y1606500D03*
X192500Y1653000D03*
Y1648000D03*
X192650Y1641500D03*
X200500Y1876500D03*
X201200Y1890500D03*
X201100Y1908800D03*
G54D16*
X31299Y230866D03*
Y220866D03*
Y210866D03*
Y348563D03*
Y338563D03*
Y358563D03*
Y903917D03*
Y923917D03*
Y913917D03*
Y1064587D03*
Y1054587D03*
Y1044587D03*
Y1619941D03*
Y1609941D03*
Y1629941D03*
Y1757638D03*
Y1747638D03*
Y1737638D03*
G54D17*
X80709Y161889D03*
Y171889D03*
Y181889D03*
Y191889D03*
Y204409D03*
Y214409D03*
Y224409D03*
Y234409D03*
Y244409D03*
Y256929D03*
Y266929D03*
Y276929D03*
Y286929D03*
X110709Y161889D03*
Y171889D03*
X100709Y161889D03*
Y171889D03*
X90709Y161889D03*
Y171889D03*
X110709Y181889D03*
Y191889D03*
X100709Y181889D03*
Y191889D03*
X90709Y181889D03*
Y191889D03*
X110709Y204409D03*
Y214409D03*
Y224409D03*
Y234409D03*
Y244409D03*
X100709Y204409D03*
Y214409D03*
Y224409D03*
Y234409D03*
Y244409D03*
X90709Y204409D03*
Y214409D03*
Y224409D03*
Y234409D03*
Y244409D03*
X110709Y256929D03*
Y266929D03*
X100709Y256929D03*
Y266929D03*
X90709Y256929D03*
Y266929D03*
X110709Y276929D03*
Y286929D03*
X100709Y276929D03*
Y286929D03*
X90709Y276929D03*
Y286929D03*
X179606Y161889D03*
Y171889D03*
X169606Y161889D03*
Y171889D03*
X159606Y161889D03*
Y171889D03*
X149606Y161889D03*
Y171889D03*
X179606Y181889D03*
Y191889D03*
X169606Y181889D03*
Y191889D03*
X159606Y181889D03*
Y191889D03*
X149606Y181889D03*
Y191889D03*
X179606Y204409D03*
Y214409D03*
Y224409D03*
Y234409D03*
Y244409D03*
X169606Y204409D03*
Y214409D03*
Y224409D03*
Y234409D03*
Y244409D03*
X159606Y204409D03*
Y214409D03*
Y224409D03*
Y234409D03*
Y244409D03*
X149606Y204409D03*
Y214409D03*
Y224409D03*
Y234409D03*
Y244409D03*
X179606Y256929D03*
Y266929D03*
X169606Y256929D03*
Y266929D03*
X159606Y256929D03*
Y266929D03*
X149606Y256929D03*
Y266929D03*
X179606Y276929D03*
Y286929D03*
X169606Y276929D03*
Y286929D03*
X159606Y276929D03*
Y286929D03*
X149606Y276929D03*
Y286929D03*
G54D18*
X96457Y1747835D03*
Y1823031D03*
X178937Y1328740D03*
X161417Y1747835D03*
Y1823031D03*
G54D19*
G01X-448201Y-66763D02*
X-480201D01*
G01X-448201Y-82763D02*
Y-162763D01*
G01Y-118263D02*
X752899D01*
G01X-448201Y-162763D02*
X752899D01*
G01X-452201Y-66763D02*
G02I-12000J0D01*
G01X-457351D02*
G02I-6850J0D01*
G01X-464201Y-82763D02*
Y-50763D01*
G01X-448201Y-82763D02*
X752899D01*
G01X-34601D02*
Y-162763D01*
G01X42720Y233990D02*
X28050Y248660D01*
Y256950D01*
G01X26450Y274750D02*
X26374Y274826D01*
X26373D01*
X23900Y277299D01*
Y319600D01*
X25500Y321200D01*
G01X28050Y256950D02*
X27300Y257700D01*
Y273900D01*
X26450Y274750D01*
G01X25500Y321200D02*
X18421Y328279D01*
Y447941D01*
X16554Y449808D01*
Y466254D01*
X28100Y477800D01*
Y528100D01*
X40000Y540000D01*
Y579000D01*
X53000Y592000D01*
Y673500D01*
G01X64500Y1165700D02*
X63900Y1166300D01*
Y1326100D01*
X9221Y1380779D01*
Y1489321D01*
X11300Y1491400D01*
Y1642300D01*
X13300Y1644300D01*
G01D02*
Y1689600D01*
G01X65200Y207850D02*
X63550D01*
X54400Y217000D01*
G01X57424Y232974D02*
Y220024D01*
X54400Y217000D01*
G01X65000Y241500D02*
Y235400D01*
G01X70600Y250500D02*
X70100Y251000D01*
Y265900D01*
X68000Y268000D01*
G01X78000Y429500D02*
X78500Y430000D01*
X111500D01*
X122500Y441000D01*
G01X77800Y540300D02*
Y532227D01*
X77842Y532185D01*
Y529781D01*
X75000Y526939D01*
Y446444D01*
X63096Y434540D01*
G01X91300Y528200D02*
Y528199D01*
X93000Y526499D01*
Y501448D01*
X82000Y490448D01*
Y483600D01*
G01X87700Y528000D02*
Y527273D01*
X89800Y525173D01*
Y502774D01*
X78200Y491174D01*
Y481700D01*
G01X77800Y540300D02*
Y543500D01*
X112501Y578201D01*
X126601D01*
X128900Y580500D01*
G01X53000Y673500D02*
Y677359D01*
X56710Y681069D01*
G01X81900Y1510200D02*
X95500Y1496600D01*
X126800D01*
X132300Y1491100D01*
G01X67700Y1568700D02*
Y1524400D01*
X81900Y1510200D01*
G01X102899Y-82763D02*
Y-162763D01*
G01X122500Y441000D02*
X117400D01*
X103525Y454875D01*
Y523425D01*
X105300Y525200D01*
G01X135500Y441000D02*
X136577D01*
X148650Y453073D01*
Y523471D01*
X132500Y539621D01*
G01X110400Y550800D02*
X105300Y545700D01*
Y525200D01*
G01X122300Y575000D02*
X123400D01*
X127900Y570500D01*
Y544221D01*
X132500Y539621D01*
G01X152500Y1456000D02*
X148700D01*
X144700Y1460000D01*
Y1460002D01*
X113452Y1491250D01*
X112750D01*
G01X87200Y1440000D02*
X87900D01*
X91300Y1436600D01*
Y1430300D01*
X89620Y1428620D01*
X89561D01*
X89112Y1428171D01*
X89000D01*
G01X99800Y1455600D02*
Y1452300D01*
X95859Y1448359D01*
G01X87200Y1440000D02*
X91400Y1444200D01*
X91700D01*
X95859Y1448359D01*
G01X134000Y1519500D02*
Y1519000D01*
X142000Y1511000D01*
Y1494800D01*
G01X108500Y1556500D02*
Y1544900D01*
X133900Y1519500D01*
X134000D01*
G01X108500Y1556500D02*
Y1569000D01*
G01X179300Y530000D02*
X179425Y529875D01*
Y450325D01*
X191400Y438350D01*
Y432405D01*
G01D02*
X191100Y432705D01*
Y433232D01*
X189332Y435000D01*
X149560D01*
X146960Y432400D01*
G01X169200Y482800D02*
Y489800D01*
X166100Y492900D01*
Y527900D01*
G01X165300Y481100D02*
Y488900D01*
X162500Y491700D01*
Y527900D01*
G01X159850Y541800D02*
X167500D01*
X179300Y530000D01*
G01X158600Y752600D02*
Y737300D01*
X162500Y733400D01*
Y701200D01*
X173100Y690600D01*
Y629292D01*
X174196Y628196D01*
G01X139900Y1415100D02*
X139000Y1414200D01*
Y1100500D01*
X146500Y1093000D01*
Y1027102D01*
X176675Y996927D01*
Y844775D01*
X158600Y826700D01*
Y752600D01*
G01X139900Y1415100D02*
Y1442378D01*
X152500Y1454978D01*
Y1456000D01*
G01D02*
Y1458898D01*
X158500Y1464898D01*
Y1466500D01*
G01X147500Y1498000D02*
Y1505000D01*
G01X143518Y1540000D02*
Y1525482D01*
X147500Y1521500D01*
Y1505000D01*
G01X153500Y1496500D02*
X157000Y1500000D01*
Y1528000D01*
G01X143518Y1567520D02*
Y1540000D01*
G01X177500Y1569500D02*
X173398D01*
X157000Y1553102D01*
Y1528000D01*
G01X217899Y-82763D02*
Y-162763D01*
G01X385399Y-82763D02*
Y-162763D01*
G01X555399Y-82763D02*
Y-162763D01*
G01X752899Y-82763D02*
Y-162763D01*
G01X780899Y-66763D02*
G02I-12000J0D01*
G01X775749D02*
G02I-6850J0D01*
G01X768899Y-82763D02*
Y-50763D01*
G01X784899Y-66763D02*
X752899D01*
M02*
